(kicad_sch (version 20230121) (generator eeschema)

  (paper "A3")

  (title_block
    (title "Scalenode CM4 Baseboard")
    (date "2024-03-26")
    (rev "1.1.3")
    (company "Antmicro")
    (comment 1 "www.antmicro.com")
  )

  (junction (at 102.87 205.74) (diameter 0) (color 0 0 0 0)
  )
  (junction (at 80.01 184.15) (diameter 0) (color 0 0 0 0)
  )
  (junction (at 294.64 166.37) (diameter 0) (color 0 0 0 0)
  )
  (junction (at 337.82 52.07) (diameter 0) (color 0 0 0 0)
  )
  (junction (at 204.47 59.69) (diameter 0) (color 0 0 0 0)
  )
  (junction (at 55.88 60.96) (diameter 0) (color 0 0 0 0)
  )
  (junction (at 139.7 83.82) (diameter 0) (color 0 0 0 0)
  )
  (junction (at 69.85 191.77) (diameter 0) (color 0 0 0 0)
  )
  (junction (at 48.26 179.07) (diameter 0) (color 0 0 0 0)
  )
  (junction (at 45.72 176.53) (diameter 0) (color 0 0 0 0)
  )
  (junction (at 64.77 68.58) (diameter 0) (color 0 0 0 0)
  )
  (junction (at 85.09 179.07) (diameter 0) (color 0 0 0 0)
  )
  (junction (at 90.17 176.53) (diameter 0) (color 0 0 0 0)
  )
  (junction (at 80.01 160.02) (diameter 0) (color 0 0 0 0)
  )
  (junction (at 50.8 184.15) (diameter 0) (color 0 0 0 0)
  )
  (junction (at 306.07 96.52) (diameter 0) (color 0 0 0 0)
  )
  (junction (at 102.87 181.61) (diameter 0) (color 0 0 0 0)
  )
  (junction (at 74.93 160.02) (diameter 0) (color 0 0 0 0)
  )
  (junction (at 95.25 160.02) (diameter 0) (color 0 0 0 0)
  )
  (junction (at 264.16 163.83) (diameter 0) (color 0 0 0 0)
  )
  (junction (at 53.34 189.23) (diameter 0) (color 0 0 0 0)
  )
  (junction (at 341.63 59.69) (diameter 0) (color 0 0 0 0)
  )
  (junction (at 208.28 52.07) (diameter 0) (color 0 0 0 0)
  )
  (junction (at 218.44 52.07) (diameter 0) (color 0 0 0 0)
  )
  (junction (at 55.88 191.77) (diameter 0) (color 0 0 0 0)
  )
  (junction (at 256.54 163.83) (diameter 0) (color 0 0 0 0)
  )
  (junction (at 111.76 205.74) (diameter 0) (color 0 0 0 0)
  )
  (junction (at 347.98 171.45) (diameter 0) (color 0 0 0 0)
  )
  (junction (at 288.29 163.83) (diameter 0) (color 0 0 0 0)
  )
  (junction (at 43.18 173.99) (diameter 0) (color 0 0 0 0)
  )
  (junction (at 111.76 196.85) (diameter 0) (color 0 0 0 0)
  )
  (junction (at 102.87 160.02) (diameter 0) (color 0 0 0 0)
  )
  (junction (at 67.31 60.96) (diameter 0) (color 0 0 0 0)
  )
  (junction (at 50.8 81.28) (diameter 0) (color 0 0 0 0)
  )
  (junction (at 345.44 52.07) (diameter 0) (color 0 0 0 0)
  )
  (junction (at 347.98 168.91) (diameter 0) (color 0 0 0 0)
  )
  (junction (at 325.12 152.4) (diameter 0) (color 0 0 0 0)
  )
  (junction (at 200.66 52.07) (diameter 0) (color 0 0 0 0)
  )
  (junction (at 74.93 189.23) (diameter 0) (color 0 0 0 0)
  )
  (junction (at 90.17 160.02) (diameter 0) (color 0 0 0 0)
  )
  (junction (at 62.23 66.04) (diameter 0) (color 0 0 0 0)
  )
  (junction (at 85.09 160.02) (diameter 0) (color 0 0 0 0)
  )
  (junction (at 241.3 96.52) (diameter 0) (color 0 0 0 0)
  )
  (junction (at 95.25 173.99) (diameter 0) (color 0 0 0 0)
  )

  (no_connect (at 137.16 66.04))
  (no_connect (at 321.31 175.26))
  (no_connect (at 321.31 177.8))
  (no_connect (at 321.31 182.88))
  (no_connect (at 48.26 73.66))
  (no_connect (at 68.58 81.28))

  (wire (pts (xy 111.76 196.85) (xy 111.76 205.74))
    (stroke (width 0) (type default))
  )
  (wire (pts (xy 241.3 86.36) (xy 241.3 90.17))
    (stroke (width 0) (type default))
  )
  (wire (pts (xy 298.45 170.18) (xy 294.64 170.18))
    (stroke (width 0) (type default))
  )
  (wire (pts (xy 345.44 52.07) (xy 337.82 52.07))
    (stroke (width 0) (type default))
  )
  (wire (pts (xy 241.3 74.93) (xy 254 74.93))
    (stroke (width 0) (type default))
  )
  (wire (pts (xy 139.7 73.66) (xy 134.62 73.66))
    (stroke (width 0) (type default))
  )
  (wire (pts (xy 139.7 91.44) (xy 139.7 92.71))
    (stroke (width 0) (type default))
  )
  (wire (pts (xy 48.26 68.58) (xy 64.77 68.58))
    (stroke (width 0) (type default))
  )
  (wire (pts (xy 85.09 160.02) (xy 90.17 160.02))
    (stroke (width 0) (type default))
  )
  (wire (pts (xy 74.93 160.02) (xy 74.93 163.83))
    (stroke (width 0) (type default))
  )
  (wire (pts (xy 64.77 76.2) (xy 64.77 68.58))
    (stroke (width 0) (type default))
  )
  (wire (pts (xy 68.58 78.74) (xy 62.23 78.74))
    (stroke (width 0) (type default))
  )
  (wire (pts (xy 111.76 205.74) (xy 111.76 208.28))
    (stroke (width 0) (type default))
  )
  (wire (pts (xy 48.26 179.07) (xy 85.09 179.07))
    (stroke (width 0) (type default))
  )
  (wire (pts (xy 208.28 52.07) (xy 218.44 52.07))
    (stroke (width 0) (type default))
  )
  (wire (pts (xy 337.82 59.69) (xy 341.63 59.69))
    (stroke (width 0) (type default))
  )
  (wire (pts (xy 102.87 160.02) (xy 95.25 160.02))
    (stroke (width 0) (type default))
  )
  (wire (pts (xy 330.2 152.4) (xy 325.12 152.4))
    (stroke (width 0) (type default))
  )
  (wire (pts (xy 327.66 77.47) (xy 331.47 77.47))
    (stroke (width 0) (type default))
  )
  (wire (pts (xy 55.88 60.96) (xy 67.31 60.96))
    (stroke (width 0) (type default))
  )
  (wire (pts (xy 102.87 181.61) (xy 102.87 160.02))
    (stroke (width 0) (type default))
  )
  (wire (pts (xy 62.23 78.74) (xy 62.23 66.04))
    (stroke (width 0) (type default))
  )
  (wire (pts (xy 38.1 179.07) (xy 48.26 179.07))
    (stroke (width 0) (type default))
  )
  (wire (pts (xy 347.98 175.26) (xy 347.98 171.45))
    (stroke (width 0) (type default))
  )
  (wire (pts (xy 271.78 175.26) (xy 287.02 175.26))
    (stroke (width 0) (type default))
  )
  (wire (pts (xy 69.85 160.02) (xy 69.85 163.83))
    (stroke (width 0) (type default))
  )
  (wire (pts (xy 53.34 189.23) (xy 74.93 189.23))
    (stroke (width 0) (type default))
  )
  (wire (pts (xy 53.34 170.18) (xy 53.34 189.23))
    (stroke (width 0) (type default))
  )
  (wire (pts (xy 264.16 163.83) (xy 264.16 165.1))
    (stroke (width 0) (type default))
  )
  (wire (pts (xy 306.07 95.25) (xy 306.07 96.52))
    (stroke (width 0) (type default))
  )
  (wire (pts (xy 69.85 168.91) (xy 69.85 191.77))
    (stroke (width 0) (type default))
  )
  (wire (pts (xy 38.1 184.15) (xy 50.8 184.15))
    (stroke (width 0) (type default))
  )
  (wire (pts (xy 143.51 205.74) (xy 111.76 205.74))
    (stroke (width 0) (type default))
  )
  (wire (pts (xy 288.29 74.93) (xy 306.07 74.93))
    (stroke (width 0) (type default))
  )
  (wire (pts (xy 102.87 157.48) (xy 102.87 160.02))
    (stroke (width 0) (type default))
  )
  (wire (pts (xy 68.58 73.66) (xy 67.31 73.66))
    (stroke (width 0) (type default))
  )
  (wire (pts (xy 118.11 179.07) (xy 85.09 179.07))
    (stroke (width 0) (type default))
  )
  (wire (pts (xy 241.3 163.83) (xy 256.54 163.83))
    (stroke (width 0) (type default))
  )
  (wire (pts (xy 102.87 201.93) (xy 102.87 205.74))
    (stroke (width 0) (type default))
  )
  (wire (pts (xy 298.45 182.88) (xy 298.45 186.69))
    (stroke (width 0) (type default))
  )
  (wire (pts (xy 118.11 184.15) (xy 80.01 184.15))
    (stroke (width 0) (type default))
  )
  (wire (pts (xy 219.71 86.36) (xy 219.71 96.52))
    (stroke (width 0) (type default))
  )
  (wire (pts (xy 38.1 191.77) (xy 55.88 191.77))
    (stroke (width 0) (type default))
  )
  (wire (pts (xy 139.7 83.82) (xy 139.7 86.36))
    (stroke (width 0) (type default))
  )
  (wire (pts (xy 345.44 52.07) (xy 345.44 53.34))
    (stroke (width 0) (type default))
  )
  (wire (pts (xy 118.11 189.23) (xy 74.93 189.23))
    (stroke (width 0) (type default))
  )
  (wire (pts (xy 80.01 160.02) (xy 85.09 160.02))
    (stroke (width 0) (type default))
  )
  (wire (pts (xy 200.66 58.42) (xy 200.66 59.69))
    (stroke (width 0) (type default))
  )
  (wire (pts (xy 347.98 165.1) (xy 347.98 168.91))
    (stroke (width 0) (type default))
  )
  (wire (pts (xy 200.66 52.07) (xy 200.66 53.34))
    (stroke (width 0) (type default))
  )
  (wire (pts (xy 341.63 59.69) (xy 345.44 59.69))
    (stroke (width 0) (type default))
  )
  (wire (pts (xy 139.7 73.66) (xy 139.7 76.2))
    (stroke (width 0) (type default))
  )
  (wire (pts (xy 151.13 63.5) (xy 147.32 63.5))
    (stroke (width 0) (type default))
  )
  (wire (pts (xy 292.1 177.8) (xy 298.45 177.8))
    (stroke (width 0) (type default))
  )
  (wire (pts (xy 321.31 168.91) (xy 335.28 168.91))
    (stroke (width 0) (type default))
  )
  (wire (pts (xy 90.17 160.02) (xy 95.25 160.02))
    (stroke (width 0) (type default))
  )
  (wire (pts (xy 340.36 171.45) (xy 347.98 171.45))
    (stroke (width 0) (type default))
  )
  (wire (pts (xy 254 83.82) (xy 241.3 83.82))
    (stroke (width 0) (type default))
  )
  (wire (pts (xy 208.28 59.69) (xy 208.28 58.42))
    (stroke (width 0) (type default))
  )
  (wire (pts (xy 294.64 170.18) (xy 294.64 166.37))
    (stroke (width 0) (type default))
  )
  (wire (pts (xy 294.64 166.37) (xy 298.45 166.37))
    (stroke (width 0) (type default))
  )
  (wire (pts (xy 67.31 60.96) (xy 67.31 73.66))
    (stroke (width 0) (type default))
  )
  (wire (pts (xy 45.72 170.18) (xy 45.72 176.53))
    (stroke (width 0) (type default))
  )
  (wire (pts (xy 200.66 59.69) (xy 204.47 59.69))
    (stroke (width 0) (type default))
  )
  (wire (pts (xy 55.88 60.96) (xy 55.88 71.12))
    (stroke (width 0) (type default))
  )
  (wire (pts (xy 43.18 173.99) (xy 95.25 173.99))
    (stroke (width 0) (type default))
  )
  (wire (pts (xy 336.55 68.58) (xy 342.9 68.58))
    (stroke (width 0) (type default))
  )
  (wire (pts (xy 90.17 168.91) (xy 90.17 176.53))
    (stroke (width 0) (type default))
  )
  (wire (pts (xy 330.2 153.67) (xy 330.2 152.4))
    (stroke (width 0) (type default))
  )
  (wire (pts (xy 38.1 194.31) (xy 71.12 194.31))
    (stroke (width 0) (type default))
  )
  (wire (pts (xy 195.58 52.07) (xy 200.66 52.07))
    (stroke (width 0) (type default))
  )
  (wire (pts (xy 204.47 68.58) (xy 219.71 68.58))
    (stroke (width 0) (type default))
  )
  (wire (pts (xy 55.88 191.77) (xy 69.85 191.77))
    (stroke (width 0) (type default))
  )
  (wire (pts (xy 111.76 186.69) (xy 111.76 196.85))
    (stroke (width 0) (type default))
  )
  (wire (pts (xy 271.78 177.8) (xy 287.02 177.8))
    (stroke (width 0) (type default))
  )
  (wire (pts (xy 306.07 83.82) (xy 290.83 83.82))
    (stroke (width 0) (type default))
  )
  (wire (pts (xy 58.42 170.18) (xy 58.42 205.74))
    (stroke (width 0) (type default))
  )
  (wire (pts (xy 38.1 176.53) (xy 45.72 176.53))
    (stroke (width 0) (type default))
  )
  (wire (pts (xy 118.11 181.61) (xy 102.87 181.61))
    (stroke (width 0) (type default))
  )
  (wire (pts (xy 74.93 160.02) (xy 80.01 160.02))
    (stroke (width 0) (type default))
  )
  (wire (pts (xy 137.16 60.96) (xy 124.46 60.96))
    (stroke (width 0) (type default))
  )
  (wire (pts (xy 64.77 68.58) (xy 85.09 68.58))
    (stroke (width 0) (type default))
  )
  (wire (pts (xy 328.93 64.77) (xy 327.66 64.77))
    (stroke (width 0) (type default))
  )
  (wire (pts (xy 335.28 171.45) (xy 321.31 171.45))
    (stroke (width 0) (type default))
  )
  (wire (pts (xy 256.54 163.83) (xy 256.54 165.1))
    (stroke (width 0) (type default))
  )
  (wire (pts (xy 218.44 52.07) (xy 218.44 64.77))
    (stroke (width 0) (type default))
  )
  (wire (pts (xy 67.31 60.96) (xy 85.09 60.96))
    (stroke (width 0) (type default))
  )
  (wire (pts (xy 118.11 176.53) (xy 90.17 176.53))
    (stroke (width 0) (type default))
  )
  (wire (pts (xy 264.16 163.83) (xy 288.29 163.83))
    (stroke (width 0) (type default))
  )
  (wire (pts (xy 330.2 160.02) (xy 330.2 158.75))
    (stroke (width 0) (type default))
  )
  (wire (pts (xy 38.1 173.99) (xy 43.18 173.99))
    (stroke (width 0) (type default))
  )
  (wire (pts (xy 50.8 78.74) (xy 50.8 81.28))
    (stroke (width 0) (type default))
  )
  (wire (pts (xy 349.25 165.1) (xy 347.98 165.1))
    (stroke (width 0) (type default))
  )
  (wire (pts (xy 118.11 196.85) (xy 111.76 196.85))
    (stroke (width 0) (type default))
  )
  (wire (pts (xy 58.42 205.74) (xy 102.87 205.74))
    (stroke (width 0) (type default))
  )
  (wire (pts (xy 204.47 59.69) (xy 208.28 59.69))
    (stroke (width 0) (type default))
  )
  (wire (pts (xy 48.26 81.28) (xy 50.8 81.28))
    (stroke (width 0) (type default))
  )
  (wire (pts (xy 355.6 171.45) (xy 347.98 171.45))
    (stroke (width 0) (type default))
  )
  (wire (pts (xy 143.51 194.31) (xy 143.51 205.74))
    (stroke (width 0) (type default))
  )
  (wire (pts (xy 241.3 95.25) (xy 241.3 96.52))
    (stroke (width 0) (type default))
  )
  (wire (pts (xy 288.29 66.04) (xy 306.07 66.04))
    (stroke (width 0) (type default))
  )
  (wire (pts (xy 294.64 152.4) (xy 325.12 152.4))
    (stroke (width 0) (type default))
  )
  (wire (pts (xy 288.29 163.83) (xy 298.45 163.83))
    (stroke (width 0) (type default))
  )
  (wire (pts (xy 241.3 71.12) (xy 306.07 71.12))
    (stroke (width 0) (type default))
  )
  (wire (pts (xy 349.25 175.26) (xy 347.98 175.26))
    (stroke (width 0) (type default))
  )
  (wire (pts (xy 204.47 77.47) (xy 219.71 77.47))
    (stroke (width 0) (type default))
  )
  (wire (pts (xy 337.82 52.07) (xy 337.82 53.34))
    (stroke (width 0) (type default))
  )
  (wire (pts (xy 68.58 76.2) (xy 64.77 76.2))
    (stroke (width 0) (type default))
  )
  (wire (pts (xy 55.88 76.2) (xy 55.88 86.36))
    (stroke (width 0) (type default))
  )
  (wire (pts (xy 325.12 152.4) (xy 325.12 163.83))
    (stroke (width 0) (type default))
  )
  (wire (pts (xy 102.87 205.74) (xy 111.76 205.74))
    (stroke (width 0) (type default))
  )
  (wire (pts (xy 55.88 170.18) (xy 55.88 191.77))
    (stroke (width 0) (type default))
  )
  (wire (pts (xy 347.98 168.91) (xy 355.6 168.91))
    (stroke (width 0) (type default))
  )
  (wire (pts (xy 288.29 152.4) (xy 288.29 163.83))
    (stroke (width 0) (type default))
  )
  (wire (pts (xy 336.55 77.47) (xy 342.9 77.47))
    (stroke (width 0) (type default))
  )
  (wire (pts (xy 219.71 96.52) (xy 241.3 96.52))
    (stroke (width 0) (type default))
  )
  (wire (pts (xy 67.31 83.82) (xy 68.58 83.82))
    (stroke (width 0) (type default))
  )
  (wire (pts (xy 48.26 170.18) (xy 48.26 179.07))
    (stroke (width 0) (type default))
  )
  (wire (pts (xy 355.6 175.26) (xy 354.33 175.26))
    (stroke (width 0) (type default))
  )
  (wire (pts (xy 241.3 80.01) (xy 306.07 80.01))
    (stroke (width 0) (type default))
  )
  (wire (pts (xy 218.44 64.77) (xy 219.71 64.77))
    (stroke (width 0) (type default))
  )
  (wire (pts (xy 325.12 163.83) (xy 321.31 163.83))
    (stroke (width 0) (type default))
  )
  (wire (pts (xy 67.31 86.36) (xy 67.31 83.82))
    (stroke (width 0) (type default))
  )
  (wire (pts (xy 350.52 52.07) (xy 345.44 52.07))
    (stroke (width 0) (type default))
  )
  (wire (pts (xy 306.07 86.36) (xy 306.07 90.17))
    (stroke (width 0) (type default))
  )
  (wire (pts (xy 102.87 181.61) (xy 102.87 196.85))
    (stroke (width 0) (type default))
  )
  (wire (pts (xy 118.11 186.69) (xy 111.76 186.69))
    (stroke (width 0) (type default))
  )
  (wire (pts (xy 337.82 52.07) (xy 328.93 52.07))
    (stroke (width 0) (type default))
  )
  (wire (pts (xy 48.26 78.74) (xy 50.8 78.74))
    (stroke (width 0) (type default))
  )
  (wire (pts (xy 118.11 173.99) (xy 95.25 173.99))
    (stroke (width 0) (type default))
  )
  (wire (pts (xy 38.1 189.23) (xy 53.34 189.23))
    (stroke (width 0) (type default))
  )
  (wire (pts (xy 76.2 194.31) (xy 118.11 194.31))
    (stroke (width 0) (type default))
  )
  (wire (pts (xy 327.66 86.36) (xy 327.66 96.52))
    (stroke (width 0) (type default))
  )
  (wire (pts (xy 80.01 160.02) (xy 80.01 163.83))
    (stroke (width 0) (type default))
  )
  (wire (pts (xy 139.7 81.28) (xy 139.7 83.82))
    (stroke (width 0) (type default))
  )
  (wire (pts (xy 328.93 52.07) (xy 328.93 64.77))
    (stroke (width 0) (type default))
  )
  (wire (pts (xy 241.3 99.06) (xy 241.3 96.52))
    (stroke (width 0) (type default))
  )
  (wire (pts (xy 340.36 168.91) (xy 347.98 168.91))
    (stroke (width 0) (type default))
  )
  (wire (pts (xy 50.8 184.15) (xy 80.01 184.15))
    (stroke (width 0) (type default))
  )
  (wire (pts (xy 95.25 168.91) (xy 95.25 173.99))
    (stroke (width 0) (type default))
  )
  (wire (pts (xy 74.93 168.91) (xy 74.93 189.23))
    (stroke (width 0) (type default))
  )
  (wire (pts (xy 43.18 170.18) (xy 43.18 173.99))
    (stroke (width 0) (type default))
  )
  (wire (pts (xy 48.26 66.04) (xy 62.23 66.04))
    (stroke (width 0) (type default))
  )
  (wire (pts (xy 80.01 168.91) (xy 80.01 184.15))
    (stroke (width 0) (type default))
  )
  (wire (pts (xy 85.09 160.02) (xy 85.09 163.83))
    (stroke (width 0) (type default))
  )
  (wire (pts (xy 85.09 168.91) (xy 85.09 179.07))
    (stroke (width 0) (type default))
  )
  (wire (pts (xy 337.82 58.42) (xy 337.82 59.69))
    (stroke (width 0) (type default))
  )
  (wire (pts (xy 345.44 58.42) (xy 345.44 59.69))
    (stroke (width 0) (type default))
  )
  (wire (pts (xy 327.66 68.58) (xy 331.47 68.58))
    (stroke (width 0) (type default))
  )
  (wire (pts (xy 294.64 166.37) (xy 294.64 152.4))
    (stroke (width 0) (type default))
  )
  (wire (pts (xy 354.33 165.1) (xy 355.6 165.1))
    (stroke (width 0) (type default))
  )
  (wire (pts (xy 95.25 160.02) (xy 95.25 163.83))
    (stroke (width 0) (type default))
  )
  (wire (pts (xy 139.7 194.31) (xy 143.51 194.31))
    (stroke (width 0) (type default))
  )
  (wire (pts (xy 208.28 52.07) (xy 208.28 53.34))
    (stroke (width 0) (type default))
  )
  (wire (pts (xy 118.11 191.77) (xy 69.85 191.77))
    (stroke (width 0) (type default))
  )
  (wire (pts (xy 306.07 99.06) (xy 306.07 96.52))
    (stroke (width 0) (type default))
  )
  (wire (pts (xy 256.54 163.83) (xy 264.16 163.83))
    (stroke (width 0) (type default))
  )
  (wire (pts (xy 264.16 170.18) (xy 264.16 171.45))
    (stroke (width 0) (type default))
  )
  (wire (pts (xy 241.3 66.04) (xy 254 66.04))
    (stroke (width 0) (type default))
  )
  (wire (pts (xy 139.7 83.82) (xy 144.78 83.82))
    (stroke (width 0) (type default))
  )
  (wire (pts (xy 69.85 160.02) (xy 74.93 160.02))
    (stroke (width 0) (type default))
  )
  (wire (pts (xy 256.54 170.18) (xy 256.54 171.45))
    (stroke (width 0) (type default))
  )
  (wire (pts (xy 292.1 175.26) (xy 298.45 175.26))
    (stroke (width 0) (type default))
  )
  (wire (pts (xy 62.23 66.04) (xy 85.09 66.04))
    (stroke (width 0) (type default))
  )
  (wire (pts (xy 48.26 60.96) (xy 55.88 60.96))
    (stroke (width 0) (type default))
  )
  (wire (pts (xy 50.8 81.28) (xy 50.8 86.36))
    (stroke (width 0) (type default))
  )
  (wire (pts (xy 45.72 176.53) (xy 90.17 176.53))
    (stroke (width 0) (type default))
  )
  (wire (pts (xy 90.17 160.02) (xy 90.17 163.83))
    (stroke (width 0) (type default))
  )
  (wire (pts (xy 200.66 52.07) (xy 208.28 52.07))
    (stroke (width 0) (type default))
  )
  (wire (pts (xy 306.07 96.52) (xy 327.66 96.52))
    (stroke (width 0) (type default))
  )
  (wire (pts (xy 50.8 170.18) (xy 50.8 184.15))
    (stroke (width 0) (type default))
  )

  (text "USB Debug UART" (at 294.64 142.24 0)
    (effects (font (size 2.54 2.54) bold) (justify left bottom))
  )
  (text "Micro USB connector" (at 41.91 41.91 0)
    (effects (font (size 2.54 2.54) bold) (justify left bottom))
  )
  (text "USB OTG bridge" (at 262.89 45.72 0)
    (effects (font (size 2.54 2.54) bold) (justify left bottom))
  )
  (text "Micro CD card slot" (at 61.468 143.764 0)
    (effects (font (size 2.54 2.54) bold) (justify left bottom))
  )

  (label "VBus_Slave" (at 85.09 60.96 180) (fields_autoplaced)
    (effects (font (size 1.27 1.27)) (justify right bottom))
  )
  (label "RPi_USB_P" (at 262.89 71.12 180) (fields_autoplaced)
    (effects (font (size 1.27 1.27)) (justify right bottom))
  )
  (label "CONN_USB_P" (at 204.47 68.58 0) (fields_autoplaced)
    (effects (font (size 1.27 1.27)) (justify left bottom))
  )
  (label "USBOTG_ID" (at 290.83 83.82 0) (fields_autoplaced)
    (effects (font (size 1.27 1.27)) (justify left bottom))
  )
  (label "Adapter_USB_P" (at 290.83 66.04 0) (fields_autoplaced)
    (effects (font (size 1.27 1.27)) (justify left bottom))
  )
  (label "VBus_Slave" (at 241.3 163.83 0) (fields_autoplaced)
    (effects (font (size 1.27 1.27)) (justify left bottom))
  )
  (label "Adapter_USB_N" (at 290.83 74.93 0) (fields_autoplaced)
    (effects (font (size 1.27 1.27)) (justify left bottom))
  )
  (label "CONN_USB_N" (at 85.09 68.58 180) (fields_autoplaced)
    (effects (font (size 1.27 1.27)) (justify right bottom))
  )
  (label "USBOTG_ID" (at 254 83.82 180) (fields_autoplaced)
    (effects (font (size 1.27 1.27)) (justify right bottom))
  )
  (label "FTDI_USB_N" (at 254 74.93 180) (fields_autoplaced)
    (effects (font (size 1.27 1.27)) (justify right bottom))
  )
  (label "CONN_USB_N" (at 204.47 77.47 0) (fields_autoplaced)
    (effects (font (size 1.27 1.27)) (justify left bottom))
  )
  (label "FTDI_USB_P" (at 254 66.04 180) (fields_autoplaced)
    (effects (font (size 1.27 1.27)) (justify right bottom))
  )
  (label "RPi_USB_N" (at 262.89 80.01 180) (fields_autoplaced)
    (effects (font (size 1.27 1.27)) (justify right bottom))
  )
  (label "FTDI_USB_P" (at 271.78 175.26 0) (fields_autoplaced)
    (effects (font (size 1.27 1.27)) (justify left bottom))
  )
  (label "VBus_Slave" (at 124.46 60.96 0) (fields_autoplaced)
    (effects (font (size 1.27 1.27)) (justify left bottom))
  )
  (label "CONN_USB_P" (at 85.09 66.04 180) (fields_autoplaced)
    (effects (font (size 1.27 1.27)) (justify right bottom))
  )
  (label "FTDI_USB_N" (at 271.78 177.8 0) (fields_autoplaced)
    (effects (font (size 1.27 1.27)) (justify left bottom))
  )

  (global_label "3V3_RPi" (shape input) (at 350.52 52.07 0) (fields_autoplaced)
    (effects (font (size 1.27 1.27)) (justify left))
    (property "Intersheetrefs" "${INTERSHEET_REFS}" (at 360.4642 51.9906 0)
      (effects (font (size 1.27 1.27)) (justify left) hide)
    )
  )
  (global_label "GPIO3" (shape output) (at 38.1 194.31 180) (fields_autoplaced)
    (effects (font (size 1.27 1.27)) (justify right))
    (property "Intersheetrefs" "${INTERSHEET_REFS}" (at 30.091 194.2306 0)
      (effects (font (size 1.27 1.27)) (justify right) hide)
    )
  )
  (global_label "SD_DAT3" (shape bidirectional) (at 38.1 176.53 180) (fields_autoplaced)
    (effects (font (size 1.27 1.27)) (justify right))
    (property "Intersheetrefs" "${INTERSHEET_REFS}" (at 27.7929 176.4506 0)
      (effects (font (size 1.27 1.27)) (justify right) hide)
    )
  )
  (global_label "Adapter_USB_N" (shape bidirectional) (at 288.29 74.93 180) (fields_autoplaced)
    (effects (font (size 1.27 1.27)) (justify right))
    (property "Intersheetrefs" "${INTERSHEET_REFS}" (at 271.7539 74.8506 0)
      (effects (font (size 1.27 1.27)) (justify right) hide)
    )
  )
  (global_label "PROG_MODE" (shape output) (at 134.62 73.66 180) (fields_autoplaced)
    (effects (font (size 1.27 1.27)) (justify right))
    (property "Intersheetrefs" "${INTERSHEET_REFS}" (at 120.9868 73.5806 0)
      (effects (font (size 1.27 1.27)) (justify right) hide)
    )
  )
  (global_label "SD_DAT1" (shape bidirectional) (at 38.1 191.77 180) (fields_autoplaced)
    (effects (font (size 1.27 1.27)) (justify right))
    (property "Intersheetrefs" "${INTERSHEET_REFS}" (at 27.7929 191.6906 0)
      (effects (font (size 1.27 1.27)) (justify right) hide)
    )
  )
  (global_label "Adapter_TXD" (shape input) (at 355.6 165.1 0) (fields_autoplaced)
    (effects (font (size 1.27 1.27)) (justify left))
    (property "Intersheetrefs" "${INTERSHEET_REFS}" (at 369.4752 165.0206 0)
      (effects (font (size 1.27 1.27)) (justify left) hide)
    )
  )
  (global_label "Adapter_RXD" (shape output) (at 355.6 175.26 0) (fields_autoplaced)
    (effects (font (size 1.27 1.27)) (justify left))
    (property "Intersheetrefs" "${INTERSHEET_REFS}" (at 369.7775 175.1806 0)
      (effects (font (size 1.27 1.27)) (justify left) hide)
    )
  )
  (global_label "PROG_MODE" (shape output) (at 151.13 63.5 0) (fields_autoplaced)
    (effects (font (size 1.27 1.27)) (justify left))
    (property "Intersheetrefs" "${INTERSHEET_REFS}" (at 164.7632 63.4206 0)
      (effects (font (size 1.27 1.27)) (justify left) hide)
    )
  )
  (global_label "Adapter_USB_P" (shape bidirectional) (at 288.29 66.04 180) (fields_autoplaced)
    (effects (font (size 1.27 1.27)) (justify right))
    (property "Intersheetrefs" "${INTERSHEET_REFS}" (at 271.8144 65.9606 0)
      (effects (font (size 1.27 1.27)) (justify right) hide)
    )
  )
  (global_label "USBOTG_ID" (shape output) (at 144.78 83.82 0) (fields_autoplaced)
    (effects (font (size 1.27 1.27)) (justify left))
    (property "Intersheetrefs" "${INTERSHEET_REFS}" (at 157.3247 83.7406 0)
      (effects (font (size 1.27 1.27)) (justify left) hide)
    )
  )
  (global_label "USB2_N" (shape bidirectional) (at 342.9 77.47 0) (fields_autoplaced)
    (effects (font (size 1.27 1.27)) (justify left))
    (property "Intersheetrefs" "${INTERSHEET_REFS}" (at 352.5418 77.3906 0)
      (effects (font (size 1.27 1.27)) (justify left) hide)
    )
  )
  (global_label "SD_DAT0" (shape bidirectional) (at 38.1 189.23 180) (fields_autoplaced)
    (effects (font (size 1.27 1.27)) (justify right))
    (property "Intersheetrefs" "${INTERSHEET_REFS}" (at 27.7929 189.1506 0)
      (effects (font (size 1.27 1.27)) (justify right) hide)
    )
  )
  (global_label "RPi_RXD" (shape output) (at 355.6 168.91 0) (fields_autoplaced)
    (effects (font (size 1.27 1.27)) (justify left))
    (property "Intersheetrefs" "${INTERSHEET_REFS}" (at 365.7861 168.8306 0)
      (effects (font (size 1.27 1.27)) (justify left) hide)
    )
  )
  (global_label "SD_DAT2" (shape bidirectional) (at 38.1 173.99 180) (fields_autoplaced)
    (effects (font (size 1.27 1.27)) (justify right))
    (property "Intersheetrefs" "${INTERSHEET_REFS}" (at 27.7929 173.9106 0)
      (effects (font (size 1.27 1.27)) (justify right) hide)
    )
  )
  (global_label "SD_CLK" (shape input) (at 38.1 184.15 180) (fields_autoplaced)
    (effects (font (size 1.27 1.27)) (justify right))
    (property "Intersheetrefs" "${INTERSHEET_REFS}" (at 28.7606 184.0706 0)
      (effects (font (size 1.27 1.27)) (justify right) hide)
    )
  )
  (global_label "USB2_P" (shape bidirectional) (at 342.9 68.58 0) (fields_autoplaced)
    (effects (font (size 1.27 1.27)) (justify left))
    (property "Intersheetrefs" "${INTERSHEET_REFS}" (at 352.4813 68.5006 0)
      (effects (font (size 1.27 1.27)) (justify left) hide)
    )
  )
  (global_label "3V3_RPi" (shape input) (at 102.87 157.48 90) (fields_autoplaced)
    (effects (font (size 1.27 1.27)) (justify left))
    (property "Intersheetrefs" "${INTERSHEET_REFS}" (at 102.7906 147.5358 90)
      (effects (font (size 1.27 1.27)) (justify left) hide)
    )
  )
  (global_label "3V3_RPi" (shape input) (at 195.58 52.07 180) (fields_autoplaced)
    (effects (font (size 1.27 1.27)) (justify right))
    (property "Intersheetrefs" "${INTERSHEET_REFS}" (at 185.6358 51.9906 0)
      (effects (font (size 1.27 1.27)) (justify right) hide)
    )
  )
  (global_label "RPi_TXD" (shape input) (at 355.6 171.45 0) (fields_autoplaced)
    (effects (font (size 1.27 1.27)) (justify left))
    (property "Intersheetrefs" "${INTERSHEET_REFS}" (at 365.4837 171.3706 0)
      (effects (font (size 1.27 1.27)) (justify left) hide)
    )
  )
  (global_label "SD_CMD" (shape input) (at 38.1 179.07 180) (fields_autoplaced)
    (effects (font (size 1.27 1.27)) (justify right))
    (property "Intersheetrefs" "${INTERSHEET_REFS}" (at 28.3372 178.9906 0)
      (effects (font (size 1.27 1.27)) (justify right) hide)
    )
  )

  (symbol (lib_id "scalenode-cm4-baseboard:MicroSD_1140084168") (at 118.11 173.99 0) (unit 1)
    (in_bom yes) (on_board yes) (dnp no) (fields_autoplaced)
    (property "Reference" "J4" (at 121.0588 166.37 0)
      (effects (font (size 1.27 1.27) (thickness 0.15)) (justify left bottom))
    )
    (property "Value" "MicroSD_1140084168" (at 121.0588 168.91 0)
      (effects (font (size 1.27 1.27) (thickness 0.15)) (justify left bottom))
    )
    (property "Footprint" "scalenode-cm4-baseboard-footprints:MicroSD_Amphenol_1140084168" (at 156.21 182.88 0)
      (effects (font (size 1.27 1.27) (thickness 0.15)) (justify left bottom) hide)
    )
    (property "Datasheet" "https://cdn.amphenol-cs.com/media/wysiwyg/files/documentation/datasheet/inputoutput/io_micro_sdcard.pdf" (at 156.21 185.42 0)
      (effects (font (size 1.27 1.27) (thickness 0.15)) (justify left bottom) hide)
    )
    (property "MPN" "1140084168" (at 156.21 187.96 0)
      (effects (font (size 1.27 1.27) (thickness 0.15)) (justify left bottom) hide)
    )
    (property "Manufacturer" "Amphenol" (at 156.21 190.5 0)
      (effects (font (size 1.27 1.27) (thickness 0.15)) (justify left bottom) hide)
    )
    (property "Author" "Antmicro" (at 156.21 193.04 0)
      (effects (font (size 1.27 1.27) (thickness 0.15)) (justify left bottom) hide)
    )
    (property "License" "Apache-2.0" (at 156.21 195.58 0)
      (effects (font (size 1.27 1.27) (thickness 0.15)) (justify left bottom) hide)
    )
    (pin "1")
    (pin "10")
    (pin "2")
    (pin "3")
    (pin "4")
    (pin "5")
    (pin "6")
    (pin "7")
    (pin "8")
    (pin "9")
    (pin "SH")
    (instances
      (project "scalenode-cm4-baseboard"
        (path ""
          (reference "J4") (unit 1)
        )
      )
    )
  )

  (symbol (lib_id "scalenode-cm4-baseboard:GND") (at 111.76 208.28 0) (unit 1)
    (in_bom yes) (on_board yes) (dnp no) (fields_autoplaced)
    (property "Reference" "#PWR013" (at 120.65 210.82 0)
      (effects (font (size 1.27 1.27) (thickness 0.15)) (justify left bottom) hide)
    )
    (property "Value" "GND" (at 109.7498 213.36 0)
      (effects (font (size 1.27 1.27) (thickness 0.15)) (justify left bottom))
    )
    (property "Footprint" "" (at 120.65 215.9 0)
      (effects (font (size 1.27 1.27) (thickness 0.15)) (justify left bottom) hide)
    )
    (property "Datasheet" "" (at 120.65 220.98 0)
      (effects (font (size 1.27 1.27) (thickness 0.15)) (justify left bottom) hide)
    )
    (property "Author" "Antmicro" (at 120.65 215.9 0)
      (effects (font (size 1.27 1.27) (thickness 0.15)) (justify left bottom) hide)
    )
    (property "License" "Apache-2.0" (at 120.65 218.44 0)
      (effects (font (size 1.27 1.27) (thickness 0.15)) (justify left bottom) hide)
    )
    (pin "1")
    (instances
      (project "scalenode-cm4-baseboard"
        (path ""
          (reference "#PWR013") (unit 1)
        )
      )
    )
  )

  (symbol (lib_id "scalenode-cm4-baseboard:GND") (at 306.07 99.06 0) (mirror y) (unit 1)
    (in_bom yes) (on_board yes) (dnp no) (fields_autoplaced)
    (property "Reference" "#PWR010" (at 297.18 101.6 0)
      (effects (font (size 1.27 1.27) (thickness 0.15)) (justify left bottom) hide)
    )
    (property "Value" "GND" (at 308.0803 104.14 0)
      (effects (font (size 1.27 1.27) (thickness 0.15)) (justify left bottom))
    )
    (property "Footprint" "" (at 297.18 106.68 0)
      (effects (font (size 1.27 1.27) (thickness 0.15)) (justify left bottom) hide)
    )
    (property "Datasheet" "" (at 297.18 111.76 0)
      (effects (font (size 1.27 1.27) (thickness 0.15)) (justify left bottom) hide)
    )
    (property "Author" "Antmicro" (at 297.18 106.68 0)
      (effects (font (size 1.27 1.27) (thickness 0.15)) (justify left bottom) hide)
    )
    (property "License" "Apache-2.0" (at 297.18 109.22 0)
      (effects (font (size 1.27 1.27) (thickness 0.15)) (justify left bottom) hide)
    )
    (pin "1")
    (instances
      (project "scalenode-cm4-baseboard"
        (path ""
          (reference "#PWR010") (unit 1)
        )
      )
    )
  )

  (symbol (lib_id "scalenode-cm4-baseboard:USB-Micro-B_Molex_473460001") (at 48.26 60.96 0) (unit 1)
    (in_bom yes) (on_board yes) (dnp no) (fields_autoplaced)
    (property "Reference" "J5" (at 36.195 53.34 0)
      (effects (font (size 1.27 1.27) (thickness 0.15)))
    )
    (property "Value" "USB-Micro-B_Molex_473460001" (at 36.195 55.88 0)
      (effects (font (size 1.27 1.27) (thickness 0.15)))
    )
    (property "Footprint" "scalenode-cm4-baseboard-footprints:USB-Micro-B_Receptacle_Molex_473460001" (at 73.025 63.5 0)
      (effects (font (size 1.27 1.27) (thickness 0.15)) (justify left bottom) hide)
    )
    (property "Datasheet" "https://www.molex.com/pdm_docs/sd/473460001_sd.pdf" (at 73.025 66.04 0)
      (effects (font (size 1.27 1.27) (thickness 0.15)) (justify left bottom) hide)
    )
    (property "MPN" "473460001" (at 73.025 68.58 0)
      (effects (font (size 1.27 1.27) (thickness 0.15)) (justify left bottom) hide)
    )
    (property "Manufacturer" "Molex" (at 73.025 71.12 0)
      (effects (font (size 1.27 1.27) (thickness 0.15)) (justify left bottom) hide)
    )
    (property "Author" "Antmicro" (at 73.025 73.66 0)
      (effects (font (size 1.27 1.27) (thickness 0.15)) (justify left bottom) hide)
    )
    (property "License" "Apache-2.0" (at 73.025 76.2 0)
      (effects (font (size 1.27 1.27) (thickness 0.15)) (justify left bottom) hide)
    )
    (pin "1")
    (pin "2")
    (pin "3")
    (pin "4")
    (pin "5")
    (pin "SH")
    (instances
      (project "scalenode-cm4-baseboard"
        (path ""
          (reference "J5") (unit 1)
        )
      )
    )
  )

  (symbol (lib_id "scalenode-cm4-baseboard:TPD4S012DRYR") (at 68.58 73.66 0) (unit 1)
    (in_bom yes) (on_board yes) (dnp no) (fields_autoplaced)
    (property "Reference" "D3" (at 82.55 77.4699 0)
      (effects (font (size 1.27 1.27) (thickness 0.15)) (justify left bottom))
    )
    (property "Value" "TPD4S012DRYR" (at 104.14 88.9 0)
      (effects (font (size 1.27 1.27) (thickness 0.15)) (justify left bottom) hide)
    )
    (property "Footprint" "scalenode-cm4-baseboard-footprints:UFDFN-6_1.45x1mm" (at 104.14 81.28 0)
      (effects (font (size 1.27 1.27) (thickness 0.15)) (justify left bottom) hide)
    )
    (property "Datasheet" "http://www.ti.com/general/docs/suppproductinfo.tsp?distId=10&gotoUrl=http%3A%2F%2Fwww.ti.com%2Flit%2Fgpn%2Ftpd4s012" (at 104.14 83.82 0)
      (effects (font (size 1.27 1.27) (thickness 0.15)) (justify left bottom) hide)
    )
    (property "Manufacturer" "Texas Instruments" (at 104.14 86.36 0)
      (effects (font (size 1.27 1.27) (thickness 0.15)) (justify left bottom) hide)
    )
    (property "MPN" "TPD4S012DRYR" (at 82.55 80.0099 0)
      (effects (font (size 1.27 1.27) (thickness 0.15)) (justify left bottom))
    )
    (property "Author" "Antmicro" (at 104.14 91.44 0)
      (effects (font (size 1.27 1.27) (thickness 0.15)) (justify left bottom) hide)
    )
    (property "License" "Apache-2.0" (at 104.14 93.98 0)
      (effects (font (size 1.27 1.27) (thickness 0.15)) (justify left bottom) hide)
    )
    (pin "1")
    (pin "2")
    (pin "3")
    (pin "4")
    (pin "5")
    (pin "6")
    (instances
      (project "scalenode-cm4-baseboard"
        (path ""
          (reference "D3") (unit 1)
        )
      )
    )
  )

  (symbol (lib_id "scalenode-cm4-baseboard:R_22R_0402") (at 336.55 68.58 0) (mirror y) (unit 1)
    (in_bom yes) (on_board yes) (dnp no)
    (property "Reference" "R7" (at 334.01 67.31 0)
      (effects (font (size 1.27 1.27) (thickness 0.15)) (justify left bottom))
    )
    (property "Value" "R_22R_0402" (at 316.23 81.28 0)
      (effects (font (size 1.27 1.27) (thickness 0.15)) (justify left bottom) hide)
    )
    (property "Footprint" "scalenode-cm4-baseboard-footprints:R_0402_1005Metric" (at 316.23 83.82 0)
      (effects (font (size 1.27 1.27) (thickness 0.15)) (justify left bottom) hide)
    )
    (property "Datasheet" "https://www.bourns.com/docs/product-datasheets/cr.pdf" (at 316.23 86.36 0)
      (effects (font (size 1.27 1.27) (thickness 0.15)) (justify left bottom) hide)
    )
    (property "Manufacturer" "Bourns" (at 316.23 91.44 0)
      (effects (font (size 1.27 1.27) (thickness 0.15)) (justify left bottom) hide)
    )
    (property "MPN" "CR0402-FX-22R0GLF" (at 316.23 88.9 0)
      (effects (font (size 1.27 1.27) (thickness 0.15)) (justify left bottom) hide)
    )
    (property "Val" "22R" (at 335.28 72.39 0)
      (effects (font (size 1.27 1.27) (thickness 0.15)) (justify left bottom))
    )
    (property "License" "Apache-2.0" (at 316.23 93.98 0)
      (effects (font (size 1.27 1.27) (thickness 0.15)) (justify left bottom) hide)
    )
    (property "Author" "Antmicro" (at 316.23 96.52 0)
      (effects (font (size 1.27 1.27) (thickness 0.15)) (justify left bottom) hide)
    )
    (property "Tolerance" "1%" (at 316.23 78.74 0)
      (effects (font (size 1.27 1.27)) (justify left bottom) hide)
    )
    (pin "1")
    (pin "2")
    (instances
      (project "scalenode-cm4-baseboard"
        (path ""
          (reference "R7") (unit 1)
        )
      )
    )
  )

  (symbol (lib_id "scalenode-cm4-baseboard:R_22R_0402") (at 336.55 77.47 0) (mirror y) (unit 1)
    (in_bom yes) (on_board yes) (dnp no)
    (property "Reference" "R8" (at 334.01 76.2 0)
      (effects (font (size 1.27 1.27) (thickness 0.15)) (justify left bottom))
    )
    (property "Value" "R_22R_0402" (at 316.23 90.17 0)
      (effects (font (size 1.27 1.27) (thickness 0.15)) (justify left bottom) hide)
    )
    (property "Footprint" "scalenode-cm4-baseboard-footprints:R_0402_1005Metric" (at 316.23 92.71 0)
      (effects (font (size 1.27 1.27) (thickness 0.15)) (justify left bottom) hide)
    )
    (property "Datasheet" "https://www.bourns.com/docs/product-datasheets/cr.pdf" (at 316.23 95.25 0)
      (effects (font (size 1.27 1.27) (thickness 0.15)) (justify left bottom) hide)
    )
    (property "Manufacturer" "Bourns" (at 316.23 100.33 0)
      (effects (font (size 1.27 1.27) (thickness 0.15)) (justify left bottom) hide)
    )
    (property "MPN" "CR0402-FX-22R0GLF" (at 316.23 97.79 0)
      (effects (font (size 1.27 1.27) (thickness 0.15)) (justify left bottom) hide)
    )
    (property "Val" "22R" (at 335.28 81.28 0)
      (effects (font (size 1.27 1.27) (thickness 0.15)) (justify left bottom))
    )
    (property "License" "Apache-2.0" (at 316.23 102.87 0)
      (effects (font (size 1.27 1.27) (thickness 0.15)) (justify left bottom) hide)
    )
    (property "Author" "Antmicro" (at 316.23 105.41 0)
      (effects (font (size 1.27 1.27) (thickness 0.15)) (justify left bottom) hide)
    )
    (property "Tolerance" "1%" (at 316.23 87.63 0)
      (effects (font (size 1.27 1.27)) (justify left bottom) hide)
    )
    (pin "1")
    (pin "2")
    (instances
      (project "scalenode-cm4-baseboard"
        (path ""
          (reference "R8") (unit 1)
        )
      )
    )
  )

  (symbol (lib_id "scalenode-cm4-baseboard:R_2k2_0402") (at 139.7 91.44 90) (unit 1)
    (in_bom yes) (on_board yes) (dnp no)
    (property "Reference" "R15" (at 140.97 88.9 90)
      (effects (font (size 1.27 1.27) (thickness 0.15)) (justify right top))
    )
    (property "Value" "R_2k2_0402" (at 152.4 71.12 0)
      (effects (font (size 1.27 1.27) (thickness 0.15)) (justify left bottom) hide)
    )
    (property "Footprint" "scalenode-cm4-baseboard-footprints:R_0402_1005Metric" (at 154.94 71.12 0)
      (effects (font (size 1.27 1.27) (thickness 0.15)) (justify left bottom) hide)
    )
    (property "Datasheet" "https://www.bourns.com/docs/product-datasheets/cr.pdf" (at 157.48 71.12 0)
      (effects (font (size 1.27 1.27) (thickness 0.15)) (justify left bottom) hide)
    )
    (property "Manufacturer" "Bourns" (at 162.56 71.12 0)
      (effects (font (size 1.27 1.27) (thickness 0.15)) (justify left bottom) hide)
    )
    (property "MPN" "CR0402-FX-2201GLF" (at 160.02 71.12 0)
      (effects (font (size 1.27 1.27) (thickness 0.15)) (justify left bottom) hide)
    )
    (property "Val" "2k2" (at 140.97 88.9 90)
      (effects (font (size 1.27 1.27) (thickness 0.15)) (justify right bottom))
    )
    (property "License" "Apache-2.0" (at 165.1 71.12 0)
      (effects (font (size 1.27 1.27) (thickness 0.15)) (justify left bottom) hide)
    )
    (property "Author" "Antmicro" (at 167.64 71.12 0)
      (effects (font (size 1.27 1.27) (thickness 0.15)) (justify left bottom) hide)
    )
    (property "Tolerance" "1%" (at 149.86 71.12 0)
      (effects (font (size 1.27 1.27)) (justify left bottom) hide)
    )
    (pin "1")
    (pin "2")
    (instances
      (project "scalenode-cm4-baseboard"
        (path ""
          (reference "R15") (unit 1)
        )
      )
    )
  )

  (symbol (lib_id "scalenode-cm4-baseboard:R_10k_0402") (at 306.07 90.17 90) (mirror x) (unit 1)
    (in_bom yes) (on_board yes) (dnp no)
    (property "Reference" "R14" (at 304.8 92.71 90)
      (effects (font (size 1.27 1.27) (thickness 0.15)) (justify left bottom))
    )
    (property "Value" "R_10k_0402" (at 318.77 110.49 0)
      (effects (font (size 1.27 1.27) (thickness 0.15)) (justify left bottom) hide)
    )
    (property "Footprint" "scalenode-cm4-baseboard-footprints:R_0402_1005Metric" (at 321.31 110.49 0)
      (effects (font (size 1.27 1.27) (thickness 0.15)) (justify left bottom) hide)
    )
    (property "Datasheet" "https://www.bourns.com/docs/product-datasheets/cr.pdf" (at 323.85 110.49 0)
      (effects (font (size 1.27 1.27) (thickness 0.15)) (justify left bottom) hide)
    )
    (property "Manufacturer" "Bourns" (at 328.93 110.49 0)
      (effects (font (size 1.27 1.27) (thickness 0.15)) (justify left bottom) hide)
    )
    (property "MPN" "CR0402-FX-1002GLF" (at 326.39 110.49 0)
      (effects (font (size 1.27 1.27) (thickness 0.15)) (justify left bottom) hide)
    )
    (property "Val" "10k" (at 304.8 92.71 90)
      (effects (font (size 1.27 1.27) (thickness 0.15)) (justify left top))
    )
    (property "License" "Apache-2.0" (at 331.47 110.49 0)
      (effects (font (size 1.27 1.27) (thickness 0.15)) (justify left bottom) hide)
    )
    (property "Author" "Antmicro" (at 334.01 110.49 0)
      (effects (font (size 1.27 1.27) (thickness 0.15)) (justify left bottom) hide)
    )
    (property "Tolerance" "1%" (at 316.23 110.49 0)
      (effects (font (size 1.27 1.27)) (justify left bottom) hide)
    )
    (pin "1")
    (pin "2")
    (instances
      (project "scalenode-cm4-baseboard"
        (path ""
          (reference "R14") (unit 1)
        )
      )
    )
  )

  (symbol (lib_id "scalenode-cm4-baseboard:R_330R_0402") (at 71.12 194.31 0) (unit 1)
    (in_bom yes) (on_board yes) (dnp no)
    (property "Reference" "R6" (at 68.58 196.85 0)
      (effects (font (size 1.27 1.27) (thickness 0.15)) (justify left bottom))
    )
    (property "Value" "R_330R_0402" (at 91.44 207.01 0)
      (effects (font (size 1.27 1.27) (thickness 0.15)) (justify left bottom) hide)
    )
    (property "Footprint" "scalenode-cm4-baseboard-footprints:R_0402_1005Metric" (at 91.44 209.55 0)
      (effects (font (size 1.27 1.27) (thickness 0.15)) (justify left bottom) hide)
    )
    (property "Datasheet" "https://www.bourns.com/docs/product-datasheets/cr.pdf" (at 91.44 212.09 0)
      (effects (font (size 1.27 1.27) (thickness 0.15)) (justify left bottom) hide)
    )
    (property "Manufacturer" "Bourns" (at 91.44 217.17 0)
      (effects (font (size 1.27 1.27) (thickness 0.15)) (justify left bottom) hide)
    )
    (property "MPN" "CR0402-FX-3300GLF" (at 91.44 214.63 0)
      (effects (font (size 1.27 1.27) (thickness 0.15)) (justify left bottom) hide)
    )
    (property "Val" "330R" (at 76.2 196.85 0)
      (effects (font (size 1.27 1.27) (thickness 0.15)) (justify left bottom))
    )
    (property "License" "Apache-2.0" (at 91.44 219.71 0)
      (effects (font (size 1.27 1.27) (thickness 0.15)) (justify left bottom) hide)
    )
    (property "Author" "Antmicro" (at 91.44 222.25 0)
      (effects (font (size 1.27 1.27) (thickness 0.15)) (justify left bottom) hide)
    )
    (property "Tolerance" "1%" (at 91.44 204.47 0)
      (effects (font (size 1.27 1.27)) (justify left bottom) hide)
    )
    (pin "1")
    (pin "2")
    (instances
      (project "scalenode-cm4-baseboard"
        (path ""
          (reference "R6") (unit 1)
        )
      )
    )
  )

  (symbol (lib_id "scalenode-cm4-baseboard:R_10k_0402") (at 69.85 163.83 270) (unit 1)
    (in_bom yes) (on_board yes) (dnp no)
    (property "Reference" "R5" (at 66.04 163.83 90)
      (effects (font (size 1.27 1.27) (thickness 0.15)) (justify left bottom))
    )
    (property "Value" "R_10k_0402" (at 57.15 184.15 0)
      (effects (font (size 1.27 1.27) (thickness 0.15)) (justify left bottom) hide)
    )
    (property "Footprint" "scalenode-cm4-baseboard-footprints:R_0402_1005Metric" (at 54.61 184.15 0)
      (effects (font (size 1.27 1.27) (thickness 0.15)) (justify left bottom) hide)
    )
    (property "Datasheet" "https://www.bourns.com/docs/product-datasheets/cr.pdf" (at 52.07 184.15 0)
      (effects (font (size 1.27 1.27) (thickness 0.15)) (justify left bottom) hide)
    )
    (property "Manufacturer" "Bourns" (at 46.99 184.15 0)
      (effects (font (size 1.27 1.27) (thickness 0.15)) (justify left bottom) hide)
    )
    (property "MPN" "CR0402-FX-1002GLF" (at 49.53 184.15 0)
      (effects (font (size 1.27 1.27) (thickness 0.15)) (justify left bottom) hide)
    )
    (property "Val" "10k" (at 66.04 170.18 90)
      (effects (font (size 1.27 1.27) (thickness 0.15)) (justify left bottom))
    )
    (property "License" "Apache-2.0" (at 44.45 184.15 0)
      (effects (font (size 1.27 1.27) (thickness 0.15)) (justify left bottom) hide)
    )
    (property "Author" "Antmicro" (at 41.91 184.15 0)
      (effects (font (size 1.27 1.27) (thickness 0.15)) (justify left bottom) hide)
    )
    (property "Tolerance" "1%" (at 59.69 184.15 0)
      (effects (font (size 1.27 1.27)) (justify left bottom) hide)
    )
    (pin "1")
    (pin "2")
    (instances
      (project "scalenode-cm4-baseboard"
        (path ""
          (reference "R5") (unit 1)
        )
      )
    )
  )

  (symbol (lib_id "scalenode-cm4-baseboard:R_10k_0402") (at 74.93 163.83 270) (unit 1)
    (in_bom yes) (on_board yes) (dnp no)
    (property "Reference" "R9" (at 72.39 163.83 90)
      (effects (font (size 1.27 1.27) (thickness 0.15)) (justify left bottom))
    )
    (property "Value" "R_10k_0402" (at 62.23 184.15 0)
      (effects (font (size 1.27 1.27) (thickness 0.15)) (justify left bottom) hide)
    )
    (property "Footprint" "scalenode-cm4-baseboard-footprints:R_0402_1005Metric" (at 59.69 184.15 0)
      (effects (font (size 1.27 1.27) (thickness 0.15)) (justify left bottom) hide)
    )
    (property "Datasheet" "https://www.bourns.com/docs/product-datasheets/cr.pdf" (at 57.15 184.15 0)
      (effects (font (size 1.27 1.27) (thickness 0.15)) (justify left bottom) hide)
    )
    (property "Manufacturer" "Bourns" (at 52.07 184.15 0)
      (effects (font (size 1.27 1.27) (thickness 0.15)) (justify left bottom) hide)
    )
    (property "MPN" "CR0402-FX-1002GLF" (at 54.61 184.15 0)
      (effects (font (size 1.27 1.27) (thickness 0.15)) (justify left bottom) hide)
    )
    (property "Val" "10k" (at 71.12 170.18 90)
      (effects (font (size 1.27 1.27) (thickness 0.15)) (justify left bottom))
    )
    (property "License" "Apache-2.0" (at 49.53 184.15 0)
      (effects (font (size 1.27 1.27) (thickness 0.15)) (justify left bottom) hide)
    )
    (property "Author" "Antmicro" (at 46.99 184.15 0)
      (effects (font (size 1.27 1.27) (thickness 0.15)) (justify left bottom) hide)
    )
    (property "Tolerance" "1%" (at 64.77 184.15 0)
      (effects (font (size 1.27 1.27)) (justify left bottom) hide)
    )
    (pin "1")
    (pin "2")
    (instances
      (project "scalenode-cm4-baseboard"
        (path ""
          (reference "R9") (unit 1)
        )
      )
    )
  )

  (symbol (lib_id "scalenode-cm4-baseboard:R_10k_0402") (at 80.01 163.83 270) (unit 1)
    (in_bom yes) (on_board yes) (dnp no)
    (property "Reference" "R10" (at 76.2 163.83 90)
      (effects (font (size 1.27 1.27) (thickness 0.15)) (justify left bottom))
    )
    (property "Value" "R_10k_0402" (at 67.31 184.15 0)
      (effects (font (size 1.27 1.27) (thickness 0.15)) (justify left bottom) hide)
    )
    (property "Footprint" "scalenode-cm4-baseboard-footprints:R_0402_1005Metric" (at 64.77 184.15 0)
      (effects (font (size 1.27 1.27) (thickness 0.15)) (justify left bottom) hide)
    )
    (property "Datasheet" "https://www.bourns.com/docs/product-datasheets/cr.pdf" (at 62.23 184.15 0)
      (effects (font (size 1.27 1.27) (thickness 0.15)) (justify left bottom) hide)
    )
    (property "Manufacturer" "Bourns" (at 57.15 184.15 0)
      (effects (font (size 1.27 1.27) (thickness 0.15)) (justify left bottom) hide)
    )
    (property "MPN" "CR0402-FX-1002GLF" (at 59.69 184.15 0)
      (effects (font (size 1.27 1.27) (thickness 0.15)) (justify left bottom) hide)
    )
    (property "Val" "10k" (at 76.2 170.18 90)
      (effects (font (size 1.27 1.27) (thickness 0.15)) (justify left bottom))
    )
    (property "License" "Apache-2.0" (at 54.61 184.15 0)
      (effects (font (size 1.27 1.27) (thickness 0.15)) (justify left bottom) hide)
    )
    (property "Author" "Antmicro" (at 52.07 184.15 0)
      (effects (font (size 1.27 1.27) (thickness 0.15)) (justify left bottom) hide)
    )
    (property "Tolerance" "1%" (at 69.85 184.15 0)
      (effects (font (size 1.27 1.27)) (justify left bottom) hide)
    )
    (pin "1")
    (pin "2")
    (instances
      (project "scalenode-cm4-baseboard"
        (path ""
          (reference "R10") (unit 1)
        )
      )
    )
  )

  (symbol (lib_id "scalenode-cm4-baseboard:R_10k_0402") (at 85.09 163.83 270) (unit 1)
    (in_bom yes) (on_board yes) (dnp no)
    (property "Reference" "R11" (at 81.28 163.83 90)
      (effects (font (size 1.27 1.27) (thickness 0.15)) (justify left bottom))
    )
    (property "Value" "R_10k_0402" (at 72.39 184.15 0)
      (effects (font (size 1.27 1.27) (thickness 0.15)) (justify left bottom) hide)
    )
    (property "Footprint" "scalenode-cm4-baseboard-footprints:R_0402_1005Metric" (at 69.85 184.15 0)
      (effects (font (size 1.27 1.27) (thickness 0.15)) (justify left bottom) hide)
    )
    (property "Datasheet" "https://www.bourns.com/docs/product-datasheets/cr.pdf" (at 67.31 184.15 0)
      (effects (font (size 1.27 1.27) (thickness 0.15)) (justify left bottom) hide)
    )
    (property "Manufacturer" "Bourns" (at 62.23 184.15 0)
      (effects (font (size 1.27 1.27) (thickness 0.15)) (justify left bottom) hide)
    )
    (property "MPN" "CR0402-FX-1002GLF" (at 64.77 184.15 0)
      (effects (font (size 1.27 1.27) (thickness 0.15)) (justify left bottom) hide)
    )
    (property "Val" "10k" (at 81.28 170.18 90)
      (effects (font (size 1.27 1.27) (thickness 0.15)) (justify left bottom))
    )
    (property "License" "Apache-2.0" (at 59.69 184.15 0)
      (effects (font (size 1.27 1.27) (thickness 0.15)) (justify left bottom) hide)
    )
    (property "Author" "Antmicro" (at 57.15 184.15 0)
      (effects (font (size 1.27 1.27) (thickness 0.15)) (justify left bottom) hide)
    )
    (property "Tolerance" "1%" (at 74.93 184.15 0)
      (effects (font (size 1.27 1.27)) (justify left bottom) hide)
    )
    (pin "1")
    (pin "2")
    (instances
      (project "scalenode-cm4-baseboard"
        (path ""
          (reference "R11") (unit 1)
        )
      )
    )
  )

  (symbol (lib_id "scalenode-cm4-baseboard:R_10k_0402") (at 90.17 163.83 270) (unit 1)
    (in_bom yes) (on_board yes) (dnp no)
    (property "Reference" "R12" (at 86.36 163.83 90)
      (effects (font (size 1.27 1.27) (thickness 0.15)) (justify left bottom))
    )
    (property "Value" "R_10k_0402" (at 77.47 184.15 0)
      (effects (font (size 1.27 1.27) (thickness 0.15)) (justify left bottom) hide)
    )
    (property "Footprint" "scalenode-cm4-baseboard-footprints:R_0402_1005Metric" (at 74.93 184.15 0)
      (effects (font (size 1.27 1.27) (thickness 0.15)) (justify left bottom) hide)
    )
    (property "Datasheet" "https://www.bourns.com/docs/product-datasheets/cr.pdf" (at 72.39 184.15 0)
      (effects (font (size 1.27 1.27) (thickness 0.15)) (justify left bottom) hide)
    )
    (property "Manufacturer" "Bourns" (at 67.31 184.15 0)
      (effects (font (size 1.27 1.27) (thickness 0.15)) (justify left bottom) hide)
    )
    (property "MPN" "CR0402-FX-1002GLF" (at 69.85 184.15 0)
      (effects (font (size 1.27 1.27) (thickness 0.15)) (justify left bottom) hide)
    )
    (property "Val" "10k" (at 86.36 170.18 90)
      (effects (font (size 1.27 1.27) (thickness 0.15)) (justify left bottom))
    )
    (property "License" "Apache-2.0" (at 64.77 184.15 0)
      (effects (font (size 1.27 1.27) (thickness 0.15)) (justify left bottom) hide)
    )
    (property "Author" "Antmicro" (at 62.23 184.15 0)
      (effects (font (size 1.27 1.27) (thickness 0.15)) (justify left bottom) hide)
    )
    (property "Tolerance" "1%" (at 80.01 184.15 0)
      (effects (font (size 1.27 1.27)) (justify left bottom) hide)
    )
    (pin "1")
    (pin "2")
    (instances
      (project "scalenode-cm4-baseboard"
        (path ""
          (reference "R12") (unit 1)
        )
      )
    )
  )

  (symbol (lib_id "scalenode-cm4-baseboard:R_10k_0402") (at 95.25 163.83 270) (unit 1)
    (in_bom yes) (on_board yes) (dnp no)
    (property "Reference" "R13" (at 91.44 163.83 90)
      (effects (font (size 1.27 1.27) (thickness 0.15)) (justify left bottom))
    )
    (property "Value" "R_10k_0402" (at 82.55 184.15 0)
      (effects (font (size 1.27 1.27) (thickness 0.15)) (justify left bottom) hide)
    )
    (property "Footprint" "scalenode-cm4-baseboard-footprints:R_0402_1005Metric" (at 80.01 184.15 0)
      (effects (font (size 1.27 1.27) (thickness 0.15)) (justify left bottom) hide)
    )
    (property "Datasheet" "https://www.bourns.com/docs/product-datasheets/cr.pdf" (at 77.47 184.15 0)
      (effects (font (size 1.27 1.27) (thickness 0.15)) (justify left bottom) hide)
    )
    (property "Manufacturer" "Bourns" (at 72.39 184.15 0)
      (effects (font (size 1.27 1.27) (thickness 0.15)) (justify left bottom) hide)
    )
    (property "MPN" "CR0402-FX-1002GLF" (at 74.93 184.15 0)
      (effects (font (size 1.27 1.27) (thickness 0.15)) (justify left bottom) hide)
    )
    (property "Val" "10k" (at 91.44 170.18 90)
      (effects (font (size 1.27 1.27) (thickness 0.15)) (justify left bottom))
    )
    (property "License" "Apache-2.0" (at 69.85 184.15 0)
      (effects (font (size 1.27 1.27) (thickness 0.15)) (justify left bottom) hide)
    )
    (property "Author" "Antmicro" (at 67.31 184.15 0)
      (effects (font (size 1.27 1.27) (thickness 0.15)) (justify left bottom) hide)
    )
    (property "Tolerance" "1%" (at 85.09 184.15 0)
      (effects (font (size 1.27 1.27)) (justify left bottom) hide)
    )
    (pin "1")
    (pin "2")
    (instances
      (project "scalenode-cm4-baseboard"
        (path ""
          (reference "R13") (unit 1)
        )
      )
    )
  )

  (symbol (lib_id "scalenode-cm4-baseboard:GND") (at 341.63 59.69 0) (unit 1)
    (in_bom yes) (on_board yes) (dnp no)
    (property "Reference" "#PWR09" (at 350.52 62.23 0)
      (effects (font (size 1.27 1.27) (thickness 0.15)) (justify left bottom) hide)
    )
    (property "Value" "GND" (at 339.6198 64.77 0)
      (effects (font (size 1.27 1.27) (thickness 0.15)) (justify left bottom))
    )
    (property "Footprint" "" (at 350.52 67.31 0)
      (effects (font (size 1.27 1.27) (thickness 0.15)) (justify left bottom) hide)
    )
    (property "Datasheet" "" (at 350.52 72.39 0)
      (effects (font (size 1.27 1.27) (thickness 0.15)) (justify left bottom) hide)
    )
    (property "Author" "Antmicro" (at 350.52 67.31 0)
      (effects (font (size 1.27 1.27) (thickness 0.15)) (justify left bottom) hide)
    )
    (property "License" "Apache-2.0" (at 350.52 69.85 0)
      (effects (font (size 1.27 1.27) (thickness 0.15)) (justify left bottom) hide)
    )
    (pin "1")
    (instances
      (project "scalenode-cm4-baseboard"
        (path ""
          (reference "#PWR09") (unit 1)
        )
      )
    )
  )

  (symbol (lib_id "scalenode-cm4-baseboard:SP3011-06UTG") (at 43.18 170.18 90) (unit 1)
    (in_bom yes) (on_board yes) (dnp no) (fields_autoplaced)
    (property "Reference" "D2" (at 58.3136 156.21 90)
      (effects (font (size 1.27 1.27) (thickness 0.15)) (justify left bottom))
    )
    (property "Value" "SP3011-06UTG" (at 52.07 156.21 0)
      (effects (font (size 1.27 1.27) (thickness 0.15)) (justify left bottom) hide)
    )
    (property "Footprint" "scalenode-cm4-baseboard-footprints:USON-14_3.5x1.35_P0.5mm" (at 54.61 156.21 0)
      (effects (font (size 1.27 1.27) (thickness 0.15)) (justify left bottom) hide)
    )
    (property "Datasheet" "https://www.littelfuse.com/media?resourcetype=datasheets&itemid=c9002a97-9994-449b-b722-f45ab5538c7f&filename=littelfuse-tvs-diode-array-sp3011-datasheet" (at 57.15 156.21 0)
      (effects (font (size 1.27 1.27) (thickness 0.15)) (justify left bottom) hide)
    )
    (property "MPN" "SP3011-06UTG" (at 58.3136 158.75 90)
      (effects (font (size 1.27 1.27) (thickness 0.15)) (justify left bottom))
    )
    (property "Manufacturer" "Littelfuse" (at 59.69 156.21 0)
      (effects (font (size 1.27 1.27) (thickness 0.15)) (justify left bottom) hide)
    )
    (property "Author" "Antmicro" (at 62.23 156.21 0)
      (effects (font (size 1.27 1.27) (thickness 0.15)) (justify left bottom) hide)
    )
    (property "License" "Apache-2.0" (at 64.77 156.21 0)
      (effects (font (size 1.27 1.27) (thickness 0.15)) (justify left bottom) hide)
    )
    (pin "11")
    (pin "12")
    (pin "13")
    (pin "14")
    (pin "1")
    (pin "10")
    (pin "2")
    (pin "3")
    (pin "4")
    (pin "5")
    (pin "6")
    (pin "7")
    (pin "8")
    (pin "9")
    (instances
      (project "scalenode-cm4-baseboard"
        (path ""
          (reference "D2") (unit 1)
        )
      )
    )
  )

  (symbol (lib_id "scalenode-cm4-baseboard:C_100n_0402") (at 337.82 53.34 270) (unit 1)
    (in_bom yes) (on_board yes) (dnp no)
    (property "Reference" "C13" (at 335.28 55.88 90)
      (effects (font (size 1.27 1.27) (thickness 0.15)) (justify right bottom))
    )
    (property "Value" "C_100n_0402" (at 327.66 73.66 0)
      (effects (font (size 1.27 1.27) (thickness 0.15)) (justify left bottom) hide)
    )
    (property "Footprint" "scalenode-cm4-baseboard-footprints:C_0402_1005Metric" (at 325.12 73.66 0)
      (effects (font (size 1.27 1.27) (thickness 0.15)) (justify left bottom) hide)
    )
    (property "Datasheet" "https://www.murata.com/products/productdetail?partno=GRM155R61H104KE14%23" (at 322.58 73.66 0)
      (effects (font (size 1.27 1.27) (thickness 0.15)) (justify left bottom) hide)
    )
    (property "Manufacturer" "Murata" (at 317.5 73.66 0)
      (effects (font (size 1.27 1.27) (thickness 0.15)) (justify left bottom) hide)
    )
    (property "MPN" "GRM155R61H104KE14D" (at 320.04 73.66 0)
      (effects (font (size 1.27 1.27) (thickness 0.15)) (justify left bottom) hide)
    )
    (property "Val" "100n" (at 335.28 55.88 90)
      (effects (font (size 1.27 1.27) (thickness 0.15)) (justify right top))
    )
    (property "License" "Apache-2.0" (at 314.96 73.66 0)
      (effects (font (size 1.27 1.27) (thickness 0.15)) (justify left bottom) hide)
    )
    (property "Author" "Antmicro" (at 312.42 73.66 0)
      (effects (font (size 1.27 1.27) (thickness 0.15)) (justify left bottom) hide)
    )
    (property "Voltage" "50V" (at 309.88 73.66 0)
      (effects (font (size 1.27 1.27)) (justify left bottom) hide)
    )
    (property "Dielectric" "X5R" (at 307.34 73.66 0)
      (effects (font (size 1.27 1.27)) (justify left bottom) hide)
    )
    (pin "1")
    (pin "2")
    (instances
      (project "scalenode-cm4-baseboard"
        (path ""
          (reference "C13") (unit 1)
        )
      )
    )
  )

  (symbol (lib_id "scalenode-cm4-baseboard:C_1u_0402") (at 345.44 53.34 270) (unit 1)
    (in_bom yes) (on_board yes) (dnp no)
    (property "Reference" "C14" (at 347.98 55.88 90)
      (effects (font (size 1.27 1.27) (thickness 0.15)) (justify left bottom))
    )
    (property "Value" "C_1u_0402" (at 335.28 73.66 0)
      (effects (font (size 1.27 1.27) (thickness 0.15)) (justify left bottom) hide)
    )
    (property "Footprint" "scalenode-cm4-baseboard-footprints:C_0402_1005Metric" (at 332.74 73.66 0)
      (effects (font (size 1.27 1.27) (thickness 0.15)) (justify left bottom) hide)
    )
    (property "Datasheet" "https://product.tdk.com/en/search/capacitor/ceramic/mlcc/info?part_no=C1005X6S1A105K050BC" (at 330.2 73.66 0)
      (effects (font (size 1.27 1.27) (thickness 0.15)) (justify left bottom) hide)
    )
    (property "Manufacturer" "TDK" (at 325.12 73.66 0)
      (effects (font (size 1.27 1.27) (thickness 0.15)) (justify left bottom) hide)
    )
    (property "MPN" "C1005X6S1A105K050BC" (at 327.66 73.66 0)
      (effects (font (size 1.27 1.27) (thickness 0.15)) (justify left bottom) hide)
    )
    (property "Val" "1u" (at 347.98 55.88 90)
      (effects (font (size 1.27 1.27) (thickness 0.15)) (justify left top))
    )
    (property "License" "Apache-2.0" (at 322.58 73.66 0)
      (effects (font (size 1.27 1.27) (thickness 0.15)) (justify left bottom) hide)
    )
    (property "Author" "Antmicro" (at 320.04 73.66 0)
      (effects (font (size 1.27 1.27) (thickness 0.15)) (justify left bottom) hide)
    )
    (property "Voltage" "" (at 317.5 73.66 0)
      (effects (font (size 1.27 1.27)) (justify left bottom) hide)
    )
    (property "Dielectric" "" (at 314.96 73.66 0)
      (effects (font (size 1.27 1.27)) (justify left bottom) hide)
    )
    (pin "1")
    (pin "2")
    (instances
      (project "scalenode-cm4-baseboard"
        (path ""
          (reference "C14") (unit 1)
        )
      )
    )
  )

  (symbol (lib_id "scalenode-cm4-baseboard:C_1u_0402") (at 102.87 201.93 90) (unit 1)
    (in_bom yes) (on_board yes) (dnp no)
    (property "Reference" "C15" (at 105.41 199.39 90)
      (effects (font (size 1.27 1.27) (thickness 0.15)) (justify right top))
    )
    (property "Value" "C_1u_0402" (at 113.03 181.61 0)
      (effects (font (size 1.27 1.27) (thickness 0.15)) (justify left bottom) hide)
    )
    (property "Footprint" "scalenode-cm4-baseboard-footprints:C_0402_1005Metric" (at 115.57 181.61 0)
      (effects (font (size 1.27 1.27) (thickness 0.15)) (justify left bottom) hide)
    )
    (property "Datasheet" "https://product.tdk.com/en/search/capacitor/ceramic/mlcc/info?part_no=C1005X6S1A105K050BC" (at 118.11 181.61 0)
      (effects (font (size 1.27 1.27) (thickness 0.15)) (justify left bottom) hide)
    )
    (property "Manufacturer" "TDK" (at 123.19 181.61 0)
      (effects (font (size 1.27 1.27) (thickness 0.15)) (justify left bottom) hide)
    )
    (property "MPN" "C1005X6S1A105K050BC" (at 120.65 181.61 0)
      (effects (font (size 1.27 1.27) (thickness 0.15)) (justify left bottom) hide)
    )
    (property "Val" "1u" (at 105.41 199.39 90)
      (effects (font (size 1.27 1.27) (thickness 0.15)) (justify right bottom))
    )
    (property "License" "Apache-2.0" (at 125.73 181.61 0)
      (effects (font (size 1.27 1.27) (thickness 0.15)) (justify left bottom) hide)
    )
    (property "Author" "Antmicro" (at 128.27 181.61 0)
      (effects (font (size 1.27 1.27) (thickness 0.15)) (justify left bottom) hide)
    )
    (property "Voltage" "" (at 130.81 181.61 0)
      (effects (font (size 1.27 1.27)) (justify left bottom) hide)
    )
    (property "Dielectric" "" (at 133.35 181.61 0)
      (effects (font (size 1.27 1.27)) (justify left bottom) hide)
    )
    (pin "1")
    (pin "2")
    (instances
      (project "scalenode-cm4-baseboard"
        (path ""
          (reference "C15") (unit 1)
        )
      )
    )
  )

  (symbol (lib_id "scalenode-cm4-baseboard:TS3USB30EDGSR") (at 306.07 66.04 0) (unit 1)
    (in_bom yes) (on_board yes) (dnp no) (fields_autoplaced)
    (property "Reference" "U1" (at 308.8979 57.15 0)
      (effects (font (size 1.27 1.27) (thickness 0.15)) (justify left bottom))
    )
    (property "Value" "TS3USB30EDGSR" (at 349.25 73.66 0)
      (effects (font (size 1.27 1.27) (thickness 0.15)) (justify left bottom) hide)
    )
    (property "Footprint" "scalenode-cm4-baseboard-footprints:MSOP-10_W3mm" (at 349.25 76.2 0)
      (effects (font (size 1.27 1.27) (thickness 0.15)) (justify left bottom) hide)
    )
    (property "Datasheet" "http://www.ti.com/general/docs/suppproductinfo.tsp?distId=10&gotoUrl=http%3A%2F%2Fwww.ti.com%2Flit%2Fgpn%2Fts3usb30e" (at 349.25 78.74 0)
      (effects (font (size 1.27 1.27) (thickness 0.15)) (justify left bottom) hide)
    )
    (property "MPN" "TS3USB30EDGSR" (at 308.8979 59.69 0)
      (effects (font (size 1.27 1.27) (thickness 0.15)) (justify left bottom))
    )
    (property "Manufacturer" "Texas Instruments" (at 349.25 81.28 0)
      (effects (font (size 1.27 1.27) (thickness 0.15)) (justify left bottom) hide)
    )
    (property "Author" "Antmicro" (at 349.25 83.82 0)
      (effects (font (size 1.27 1.27) (thickness 0.15)) (justify left bottom) hide)
    )
    (property "License" "Apache-2.0" (at 349.25 86.36 0)
      (effects (font (size 1.27 1.27) (thickness 0.15)) (justify left bottom) hide)
    )
    (pin "1")
    (pin "10")
    (pin "2")
    (pin "3")
    (pin "4")
    (pin "5")
    (pin "6")
    (pin "7")
    (pin "8")
    (pin "9")
    (instances
      (project "scalenode-cm4-baseboard"
        (path ""
          (reference "U1") (unit 1)
        )
      )
    )
  )

  (symbol (lib_id "scalenode-cm4-baseboard:GND") (at 241.3 99.06 0) (unit 1)
    (in_bom yes) (on_board yes) (dnp no) (fields_autoplaced)
    (property "Reference" "#PWR041" (at 250.19 101.6 0)
      (effects (font (size 1.27 1.27) (thickness 0.15)) (justify left bottom) hide)
    )
    (property "Value" "GND" (at 239.2898 104.14 0)
      (effects (font (size 1.27 1.27) (thickness 0.15)) (justify left bottom))
    )
    (property "Footprint" "" (at 250.19 106.68 0)
      (effects (font (size 1.27 1.27) (thickness 0.15)) (justify left bottom) hide)
    )
    (property "Datasheet" "" (at 250.19 111.76 0)
      (effects (font (size 1.27 1.27) (thickness 0.15)) (justify left bottom) hide)
    )
    (property "Author" "Antmicro" (at 250.19 106.68 0)
      (effects (font (size 1.27 1.27) (thickness 0.15)) (justify left bottom) hide)
    )
    (property "License" "Apache-2.0" (at 250.19 109.22 0)
      (effects (font (size 1.27 1.27) (thickness 0.15)) (justify left bottom) hide)
    )
    (pin "1")
    (instances
      (project "scalenode-cm4-baseboard"
        (path ""
          (reference "#PWR041") (unit 1)
        )
      )
    )
  )

  (symbol (lib_id "scalenode-cm4-baseboard:R_10k_0402") (at 241.3 90.17 270) (unit 1)
    (in_bom yes) (on_board yes) (dnp no)
    (property "Reference" "R55" (at 242.57 92.71 90)
      (effects (font (size 1.27 1.27) (thickness 0.15)) (justify left bottom))
    )
    (property "Value" "R_10k_0402" (at 228.6 110.49 0)
      (effects (font (size 1.27 1.27) (thickness 0.15)) (justify left bottom) hide)
    )
    (property "Footprint" "scalenode-cm4-baseboard-footprints:R_0402_1005Metric" (at 226.06 110.49 0)
      (effects (font (size 1.27 1.27) (thickness 0.15)) (justify left bottom) hide)
    )
    (property "Datasheet" "https://www.bourns.com/docs/product-datasheets/cr.pdf" (at 223.52 110.49 0)
      (effects (font (size 1.27 1.27) (thickness 0.15)) (justify left bottom) hide)
    )
    (property "Manufacturer" "Bourns" (at 218.44 110.49 0)
      (effects (font (size 1.27 1.27) (thickness 0.15)) (justify left bottom) hide)
    )
    (property "MPN" "CR0402-FX-1002GLF" (at 220.98 110.49 0)
      (effects (font (size 1.27 1.27) (thickness 0.15)) (justify left bottom) hide)
    )
    (property "Val" "10k" (at 242.57 92.71 90)
      (effects (font (size 1.27 1.27) (thickness 0.15)) (justify left top))
    )
    (property "License" "Apache-2.0" (at 215.9 110.49 0)
      (effects (font (size 1.27 1.27) (thickness 0.15)) (justify left bottom) hide)
    )
    (property "Author" "Antmicro" (at 213.36 110.49 0)
      (effects (font (size 1.27 1.27) (thickness 0.15)) (justify left bottom) hide)
    )
    (property "Tolerance" "1%" (at 231.14 110.49 0)
      (effects (font (size 1.27 1.27)) (justify left bottom) hide)
    )
    (pin "1")
    (pin "2")
    (instances
      (project "scalenode-cm4-baseboard"
        (path ""
          (reference "R55") (unit 1)
        )
      )
    )
  )

  (symbol (lib_id "scalenode-cm4-baseboard:C_100n_0402") (at 200.66 58.42 90) (unit 1)
    (in_bom yes) (on_board yes) (dnp no)
    (property "Reference" "C51" (at 198.12 55.88 90)
      (effects (font (size 1.27 1.27) (thickness 0.15)) (justify left top))
    )
    (property "Value" "C_100n_0402" (at 210.82 38.1 0)
      (effects (font (size 1.27 1.27) (thickness 0.15)) (justify left bottom) hide)
    )
    (property "Footprint" "scalenode-cm4-baseboard-footprints:C_0402_1005Metric" (at 213.36 38.1 0)
      (effects (font (size 1.27 1.27) (thickness 0.15)) (justify left bottom) hide)
    )
    (property "Datasheet" "https://www.murata.com/products/productdetail?partno=GRM155R61H104KE14%23" (at 215.9 38.1 0)
      (effects (font (size 1.27 1.27) (thickness 0.15)) (justify left bottom) hide)
    )
    (property "Manufacturer" "Murata" (at 220.98 38.1 0)
      (effects (font (size 1.27 1.27) (thickness 0.15)) (justify left bottom) hide)
    )
    (property "MPN" "GRM155R61H104KE14D" (at 218.44 38.1 0)
      (effects (font (size 1.27 1.27) (thickness 0.15)) (justify left bottom) hide)
    )
    (property "Val" "100n" (at 198.12 55.88 90)
      (effects (font (size 1.27 1.27) (thickness 0.15)) (justify left bottom))
    )
    (property "License" "Apache-2.0" (at 223.52 38.1 0)
      (effects (font (size 1.27 1.27) (thickness 0.15)) (justify left bottom) hide)
    )
    (property "Author" "Antmicro" (at 226.06 38.1 0)
      (effects (font (size 1.27 1.27) (thickness 0.15)) (justify left bottom) hide)
    )
    (property "Voltage" "50V" (at 228.6 38.1 0)
      (effects (font (size 1.27 1.27)) (justify left bottom) hide)
    )
    (property "Dielectric" "X5R" (at 231.14 38.1 0)
      (effects (font (size 1.27 1.27)) (justify left bottom) hide)
    )
    (pin "1")
    (pin "2")
    (instances
      (project "scalenode-cm4-baseboard"
        (path ""
          (reference "C51") (unit 1)
        )
      )
    )
  )

  (symbol (lib_id "scalenode-cm4-baseboard:GND") (at 204.47 59.69 0) (unit 1)
    (in_bom yes) (on_board yes) (dnp no) (fields_autoplaced)
    (property "Reference" "#PWR023" (at 213.36 62.23 0)
      (effects (font (size 1.27 1.27) (thickness 0.15)) (justify left bottom) hide)
    )
    (property "Value" "GND" (at 202.4598 64.77 0)
      (effects (font (size 1.27 1.27) (thickness 0.15)) (justify left bottom))
    )
    (property "Footprint" "" (at 213.36 67.31 0)
      (effects (font (size 1.27 1.27) (thickness 0.15)) (justify left bottom) hide)
    )
    (property "Datasheet" "" (at 213.36 72.39 0)
      (effects (font (size 1.27 1.27) (thickness 0.15)) (justify left bottom) hide)
    )
    (property "Author" "Antmicro" (at 213.36 67.31 0)
      (effects (font (size 1.27 1.27) (thickness 0.15)) (justify left bottom) hide)
    )
    (property "License" "Apache-2.0" (at 213.36 69.85 0)
      (effects (font (size 1.27 1.27) (thickness 0.15)) (justify left bottom) hide)
    )
    (pin "1")
    (instances
      (project "scalenode-cm4-baseboard"
        (path ""
          (reference "#PWR023") (unit 1)
        )
      )
    )
  )

  (symbol (lib_id "scalenode-cm4-baseboard:C_1u_0402") (at 208.28 58.42 90) (unit 1)
    (in_bom yes) (on_board yes) (dnp no)
    (property "Reference" "C52" (at 210.82 55.88 90)
      (effects (font (size 1.27 1.27) (thickness 0.15)) (justify right top))
    )
    (property "Value" "C_1u_0402" (at 218.44 38.1 0)
      (effects (font (size 1.27 1.27) (thickness 0.15)) (justify left bottom) hide)
    )
    (property "Footprint" "scalenode-cm4-baseboard-footprints:C_0402_1005Metric" (at 220.98 38.1 0)
      (effects (font (size 1.27 1.27) (thickness 0.15)) (justify left bottom) hide)
    )
    (property "Datasheet" "https://product.tdk.com/en/search/capacitor/ceramic/mlcc/info?part_no=C1005X6S1A105K050BC" (at 223.52 38.1 0)
      (effects (font (size 1.27 1.27) (thickness 0.15)) (justify left bottom) hide)
    )
    (property "Manufacturer" "TDK" (at 228.6 38.1 0)
      (effects (font (size 1.27 1.27) (thickness 0.15)) (justify left bottom) hide)
    )
    (property "MPN" "C1005X6S1A105K050BC" (at 226.06 38.1 0)
      (effects (font (size 1.27 1.27) (thickness 0.15)) (justify left bottom) hide)
    )
    (property "Val" "1u" (at 210.82 55.88 90)
      (effects (font (size 1.27 1.27) (thickness 0.15)) (justify right bottom))
    )
    (property "License" "Apache-2.0" (at 231.14 38.1 0)
      (effects (font (size 1.27 1.27) (thickness 0.15)) (justify left bottom) hide)
    )
    (property "Author" "Antmicro" (at 233.68 38.1 0)
      (effects (font (size 1.27 1.27) (thickness 0.15)) (justify left bottom) hide)
    )
    (property "Voltage" "" (at 236.22 38.1 0)
      (effects (font (size 1.27 1.27)) (justify left bottom) hide)
    )
    (property "Dielectric" "" (at 238.76 38.1 0)
      (effects (font (size 1.27 1.27)) (justify left bottom) hide)
    )
    (pin "1")
    (pin "2")
    (instances
      (project "scalenode-cm4-baseboard"
        (path ""
          (reference "C52") (unit 1)
        )
      )
    )
  )

  (symbol (lib_id "scalenode-cm4-baseboard:TS3USB30EDGSR") (at 241.3 66.04 0) (mirror y) (unit 1)
    (in_bom yes) (on_board yes) (dnp no) (fields_autoplaced)
    (property "Reference" "U5" (at 238.4722 57.15 0)
      (effects (font (size 1.27 1.27) (thickness 0.15)) (justify left bottom))
    )
    (property "Value" "TS3USB30EDGSR" (at 198.12 73.66 0)
      (effects (font (size 1.27 1.27) (thickness 0.15)) (justify left bottom) hide)
    )
    (property "Footprint" "scalenode-cm4-baseboard-footprints:MSOP-10_W3mm" (at 198.12 76.2 0)
      (effects (font (size 1.27 1.27) (thickness 0.15)) (justify left bottom) hide)
    )
    (property "Datasheet" "http://www.ti.com/general/docs/suppproductinfo.tsp?distId=10&gotoUrl=http%3A%2F%2Fwww.ti.com%2Flit%2Fgpn%2Fts3usb30e" (at 198.12 78.74 0)
      (effects (font (size 1.27 1.27) (thickness 0.15)) (justify left bottom) hide)
    )
    (property "MPN" "TS3USB30EDGSR" (at 238.4722 59.69 0)
      (effects (font (size 1.27 1.27) (thickness 0.15)) (justify left bottom))
    )
    (property "Manufacturer" "Texas Instruments" (at 198.12 81.28 0)
      (effects (font (size 1.27 1.27) (thickness 0.15)) (justify left bottom) hide)
    )
    (property "Author" "Antmicro" (at 198.12 83.82 0)
      (effects (font (size 1.27 1.27) (thickness 0.15)) (justify left bottom) hide)
    )
    (property "License" "Apache-2.0" (at 198.12 86.36 0)
      (effects (font (size 1.27 1.27) (thickness 0.15)) (justify left bottom) hide)
    )
    (pin "1")
    (pin "10")
    (pin "2")
    (pin "3")
    (pin "4")
    (pin "5")
    (pin "6")
    (pin "7")
    (pin "8")
    (pin "9")
    (instances
      (project "scalenode-cm4-baseboard"
        (path ""
          (reference "U5") (unit 1)
        )
      )
    )
  )

  (symbol (lib_id "scalenode-cm4-baseboard:R_1k1_0402") (at 139.7 81.28 270) (mirror x) (unit 1)
    (in_bom yes) (on_board yes) (dnp no)
    (property "Reference" "R16" (at 140.97 78.74 90)
      (effects (font (size 1.27 1.27) (thickness 0.15)) (justify left top))
    )
    (property "Value" "R_1k1_0402" (at 127 60.96 0)
      (effects (font (size 1.27 1.27) (thickness 0.15)) (justify left bottom) hide)
    )
    (property "Footprint" "scalenode-cm4-baseboard-footprints:R_0402_1005Metric" (at 124.46 60.96 0)
      (effects (font (size 1.27 1.27) (thickness 0.15)) (justify left bottom) hide)
    )
    (property "Datasheet" "https://www.bourns.com/docs/product-datasheets/cr.pdf" (at 121.92 60.96 0)
      (effects (font (size 1.27 1.27) (thickness 0.15)) (justify left bottom) hide)
    )
    (property "Manufacturer" "Bourns" (at 116.84 60.96 0)
      (effects (font (size 1.27 1.27) (thickness 0.15)) (justify left bottom) hide)
    )
    (property "MPN" "CR0402-FX-1101GLF" (at 119.38 60.96 0)
      (effects (font (size 1.27 1.27) (thickness 0.15)) (justify left bottom) hide)
    )
    (property "Val" "1k1" (at 140.97 78.74 90)
      (effects (font (size 1.27 1.27) (thickness 0.15)) (justify left bottom))
    )
    (property "License" "Apache-2.0" (at 114.3 60.96 0)
      (effects (font (size 1.27 1.27) (thickness 0.15)) (justify left bottom) hide)
    )
    (property "Author" "Antmicro" (at 111.76 60.96 0)
      (effects (font (size 1.27 1.27) (thickness 0.15)) (justify left bottom) hide)
    )
    (property "Tolerance" "1%" (at 129.54 60.96 0)
      (effects (font (size 1.27 1.27)) (justify left bottom) hide)
    )
    (pin "1")
    (pin "2")
    (instances
      (project "scalenode-cm4-baseboard"
        (path ""
          (reference "R16") (unit 1)
        )
      )
    )
  )

  (symbol (lib_id "scalenode-cm4-baseboard:FT234XD-R") (at 298.45 163.83 0) (unit 1)
    (in_bom yes) (on_board yes) (dnp no) (fields_autoplaced)
    (property "Reference" "U6" (at 304.3017 156.21 0)
      (effects (font (size 1.27 1.27) (thickness 0.15)) (justify left bottom))
    )
    (property "Value" "FT234XD-R" (at 334.01 171.45 0)
      (effects (font (size 1.27 1.27) (thickness 0.15)) (justify left bottom) hide)
    )
    (property "Footprint" "scalenode-cm4-baseboard-footprints:DFN-12-1EP_3x3mm" (at 334.01 173.99 0)
      (effects (font (size 1.27 1.27) (thickness 0.15)) (justify left bottom) hide)
    )
    (property "Datasheet" "http://www.ftdichip.com/Support/Documents/DataSheets/ICs/DS_FT234XD.pdf" (at 334.01 176.53 0)
      (effects (font (size 1.27 1.27) (thickness 0.15)) (justify left bottom) hide)
    )
    (property "Manufacturer" "FTDI Chip" (at 334.01 179.07 0)
      (effects (font (size 1.27 1.27) (thickness 0.15)) (justify left bottom) hide)
    )
    (property "MPN" "FT234XD-R" (at 304.3017 158.75 0)
      (effects (font (size 1.27 1.27) (thickness 0.15)) (justify left bottom))
    )
    (property "License" "Apache-2.0" (at 334.01 184.15 0)
      (effects (font (size 1.27 1.27) (thickness 0.15)) (justify left bottom) hide)
    )
    (property "Author" "Antmicro" (at 334.01 181.61 0)
      (effects (font (size 1.27 1.27) (thickness 0.15)) (justify left bottom) hide)
    )
    (pin "1")
    (pin "10")
    (pin "11")
    (pin "12")
    (pin "13")
    (pin "2")
    (pin "3")
    (pin "4")
    (pin "5")
    (pin "6")
    (pin "7")
    (pin "8")
    (pin "9")
    (instances
      (project "scalenode-cm4-baseboard"
        (path ""
          (reference "U6") (unit 1)
        )
      )
    )
  )

  (symbol (lib_id "scalenode-cm4-baseboard:R_22R_0402") (at 287.02 175.26 0) (unit 1)
    (in_bom yes) (on_board yes) (dnp no)
    (property "Reference" "R59" (at 285.75 175.26 0)
      (effects (font (size 1.27 1.27) (thickness 0.15)) (justify bottom))
    )
    (property "Value" "R_22R_0402" (at 307.34 187.96 0)
      (effects (font (size 1.27 1.27) (thickness 0.15)) (justify left bottom) hide)
    )
    (property "Footprint" "scalenode-cm4-baseboard-footprints:R_0402_1005Metric" (at 307.34 190.5 0)
      (effects (font (size 1.27 1.27) (thickness 0.15)) (justify left bottom) hide)
    )
    (property "Datasheet" "https://www.bourns.com/docs/product-datasheets/cr.pdf" (at 307.34 193.04 0)
      (effects (font (size 1.27 1.27) (thickness 0.15)) (justify left bottom) hide)
    )
    (property "Manufacturer" "Bourns" (at 307.34 198.12 0)
      (effects (font (size 1.27 1.27) (thickness 0.15)) (justify left bottom) hide)
    )
    (property "MPN" "CR0402-FX-22R0GLF" (at 307.34 195.58 0)
      (effects (font (size 1.27 1.27) (thickness 0.15)) (justify left bottom) hide)
    )
    (property "Val" "22R" (at 293.37 175.26 0)
      (effects (font (size 1.27 1.27) (thickness 0.15)) (justify bottom))
    )
    (property "License" "Apache-2.0" (at 307.34 200.66 0)
      (effects (font (size 1.27 1.27) (thickness 0.15)) (justify left bottom) hide)
    )
    (property "Author" "Antmicro" (at 307.34 203.2 0)
      (effects (font (size 1.27 1.27) (thickness 0.15)) (justify left bottom) hide)
    )
    (property "Tolerance" "1%" (at 307.34 185.42 0)
      (effects (font (size 1.27 1.27)) (justify left bottom) hide)
    )
    (pin "1")
    (pin "2")
    (instances
      (project "scalenode-cm4-baseboard"
        (path ""
          (reference "R59") (unit 1)
        )
      )
    )
  )

  (symbol (lib_id "scalenode-cm4-baseboard:R_22R_0402") (at 287.02 177.8 0) (unit 1)
    (in_bom yes) (on_board yes) (dnp no)
    (property "Reference" "R58" (at 285.75 177.8 0)
      (effects (font (size 1.27 1.27) (thickness 0.15)) (justify top))
    )
    (property "Value" "R_22R_0402" (at 307.34 190.5 0)
      (effects (font (size 1.27 1.27) (thickness 0.15)) (justify left bottom) hide)
    )
    (property "Footprint" "scalenode-cm4-baseboard-footprints:R_0402_1005Metric" (at 307.34 193.04 0)
      (effects (font (size 1.27 1.27) (thickness 0.15)) (justify left bottom) hide)
    )
    (property "Datasheet" "https://www.bourns.com/docs/product-datasheets/cr.pdf" (at 307.34 195.58 0)
      (effects (font (size 1.27 1.27) (thickness 0.15)) (justify left bottom) hide)
    )
    (property "Manufacturer" "Bourns" (at 307.34 200.66 0)
      (effects (font (size 1.27 1.27) (thickness 0.15)) (justify left bottom) hide)
    )
    (property "MPN" "CR0402-FX-22R0GLF" (at 307.34 198.12 0)
      (effects (font (size 1.27 1.27) (thickness 0.15)) (justify left bottom) hide)
    )
    (property "Val" "22R" (at 293.37 177.8 0)
      (effects (font (size 1.27 1.27) (thickness 0.15)) (justify top))
    )
    (property "License" "Apache-2.0" (at 307.34 203.2 0)
      (effects (font (size 1.27 1.27) (thickness 0.15)) (justify left bottom) hide)
    )
    (property "Author" "Antmicro" (at 307.34 205.74 0)
      (effects (font (size 1.27 1.27) (thickness 0.15)) (justify left bottom) hide)
    )
    (property "Tolerance" "1%" (at 307.34 187.96 0)
      (effects (font (size 1.27 1.27)) (justify left bottom) hide)
    )
    (pin "1")
    (pin "2")
    (instances
      (project "scalenode-cm4-baseboard"
        (path ""
          (reference "R58") (unit 1)
        )
      )
    )
  )

  (symbol (lib_id "scalenode-cm4-baseboard:GND") (at 298.45 186.69 0) (unit 1)
    (in_bom yes) (on_board yes) (dnp no) (fields_autoplaced)
    (property "Reference" "#PWR045" (at 307.34 189.23 0)
      (effects (font (size 1.27 1.27) (thickness 0.15)) (justify left bottom) hide)
    )
    (property "Value" "GND" (at 296.4398 191.77 0)
      (effects (font (size 1.27 1.27) (thickness 0.15)) (justify left bottom))
    )
    (property "Footprint" "" (at 307.34 194.31 0)
      (effects (font (size 1.27 1.27) (thickness 0.15)) (justify left bottom) hide)
    )
    (property "Datasheet" "" (at 307.34 199.39 0)
      (effects (font (size 1.27 1.27) (thickness 0.15)) (justify left bottom) hide)
    )
    (property "Author" "Antmicro" (at 307.34 194.31 0)
      (effects (font (size 1.27 1.27) (thickness 0.15)) (justify left bottom) hide)
    )
    (property "License" "Apache-2.0" (at 307.34 196.85 0)
      (effects (font (size 1.27 1.27) (thickness 0.15)) (justify left bottom) hide)
    )
    (pin "1")
    (instances
      (project "scalenode-cm4-baseboard"
        (path ""
          (reference "#PWR045") (unit 1)
        )
      )
    )
  )

  (symbol (lib_id "scalenode-cm4-baseboard:C_100n_0402") (at 330.2 153.67 90) (mirror x) (unit 1)
    (in_bom yes) (on_board yes) (dnp no)
    (property "Reference" "C55" (at 332.74 156.21 90)
      (effects (font (size 1.27 1.27) (thickness 0.15)) (justify right bottom))
    )
    (property "Value" "C_100n_0402" (at 340.36 173.99 0)
      (effects (font (size 1.27 1.27) (thickness 0.15)) (justify left bottom) hide)
    )
    (property "Footprint" "scalenode-cm4-baseboard-footprints:C_0402_1005Metric" (at 342.9 173.99 0)
      (effects (font (size 1.27 1.27) (thickness 0.15)) (justify left bottom) hide)
    )
    (property "Datasheet" "https://www.murata.com/products/productdetail?partno=GRM155R61H104KE14%23" (at 345.44 173.99 0)
      (effects (font (size 1.27 1.27) (thickness 0.15)) (justify left bottom) hide)
    )
    (property "Manufacturer" "Murata" (at 350.52 173.99 0)
      (effects (font (size 1.27 1.27) (thickness 0.15)) (justify left bottom) hide)
    )
    (property "MPN" "GRM155R61H104KE14D" (at 347.98 173.99 0)
      (effects (font (size 1.27 1.27) (thickness 0.15)) (justify left bottom) hide)
    )
    (property "Val" "100n" (at 332.74 156.21 90)
      (effects (font (size 1.27 1.27) (thickness 0.15)) (justify right top))
    )
    (property "License" "Apache-2.0" (at 353.06 173.99 0)
      (effects (font (size 1.27 1.27) (thickness 0.15)) (justify left bottom) hide)
    )
    (property "Author" "Antmicro" (at 355.6 173.99 0)
      (effects (font (size 1.27 1.27) (thickness 0.15)) (justify left bottom) hide)
    )
    (property "Voltage" "50V" (at 358.14 173.99 0)
      (effects (font (size 1.27 1.27)) (justify left bottom) hide)
    )
    (property "Dielectric" "X5R" (at 360.68 173.99 0)
      (effects (font (size 1.27 1.27)) (justify left bottom) hide)
    )
    (pin "1")
    (pin "2")
    (instances
      (project "scalenode-cm4-baseboard"
        (path ""
          (reference "C55") (unit 1)
        )
      )
    )
  )

  (symbol (lib_id "scalenode-cm4-baseboard:GND") (at 330.2 160.02 0) (unit 1)
    (in_bom yes) (on_board yes) (dnp no) (fields_autoplaced)
    (property "Reference" "#PWR046" (at 339.09 162.56 0)
      (effects (font (size 1.27 1.27) (thickness 0.15)) (justify left bottom) hide)
    )
    (property "Value" "GND" (at 339.09 165.1 0)
      (effects (font (size 1.27 1.27) (thickness 0.15)) (justify left bottom))
    )
    (property "Footprint" "" (at 339.09 167.64 0)
      (effects (font (size 1.27 1.27) (thickness 0.15)) (justify left bottom) hide)
    )
    (property "Datasheet" "" (at 339.09 172.72 0)
      (effects (font (size 1.27 1.27) (thickness 0.15)) (justify left bottom) hide)
    )
    (property "Author" "Antmicro" (at 339.09 167.64 0)
      (effects (font (size 1.27 1.27) (thickness 0.15)) (justify left bottom) hide)
    )
    (property "License" "Apache-2.0" (at 339.09 170.18 0)
      (effects (font (size 1.27 1.27) (thickness 0.15)) (justify left bottom) hide)
    )
    (pin "1")
    (instances
      (project "scalenode-cm4-baseboard"
        (path ""
          (reference "#PWR046") (unit 1)
        )
      )
    )
  )

  (symbol (lib_id "scalenode-cm4-baseboard:C_100n_0402") (at 264.16 170.18 90) (unit 1)
    (in_bom yes) (on_board yes) (dnp no) (fields_autoplaced)
    (property "Reference" "C54" (at 271.78 166.3635 90)
      (effects (font (size 1.27 1.27) (thickness 0.15)) (justify left bottom))
    )
    (property "Value" "C_100n_0402" (at 274.32 149.86 0)
      (effects (font (size 1.27 1.27) (thickness 0.15)) (justify left bottom) hide)
    )
    (property "Footprint" "scalenode-cm4-baseboard-footprints:C_0402_1005Metric" (at 276.86 149.86 0)
      (effects (font (size 1.27 1.27) (thickness 0.15)) (justify left bottom) hide)
    )
    (property "Datasheet" "https://www.murata.com/products/productdetail?partno=GRM155R61H104KE14%23" (at 279.4 149.86 0)
      (effects (font (size 1.27 1.27) (thickness 0.15)) (justify left bottom) hide)
    )
    (property "Manufacturer" "Murata" (at 284.48 149.86 0)
      (effects (font (size 1.27 1.27) (thickness 0.15)) (justify left bottom) hide)
    )
    (property "MPN" "GRM155R61H104KE14D" (at 281.94 149.86 0)
      (effects (font (size 1.27 1.27) (thickness 0.15)) (justify left bottom) hide)
    )
    (property "Val" "100n" (at 271.78 168.9035 90)
      (effects (font (size 1.27 1.27) (thickness 0.15)) (justify left bottom))
    )
    (property "License" "Apache-2.0" (at 287.02 149.86 0)
      (effects (font (size 1.27 1.27) (thickness 0.15)) (justify left bottom) hide)
    )
    (property "Author" "Antmicro" (at 289.56 149.86 0)
      (effects (font (size 1.27 1.27) (thickness 0.15)) (justify left bottom) hide)
    )
    (property "Voltage" "50V" (at 292.1 149.86 0)
      (effects (font (size 1.27 1.27)) (justify left bottom) hide)
    )
    (property "Dielectric" "X5R" (at 294.64 149.86 0)
      (effects (font (size 1.27 1.27)) (justify left bottom) hide)
    )
    (pin "1")
    (pin "2")
    (instances
      (project "scalenode-cm4-baseboard"
        (path ""
          (reference "C54") (unit 1)
        )
      )
    )
  )

  (symbol (lib_id "scalenode-cm4-baseboard:C_1u_0402") (at 256.54 170.18 90) (unit 1)
    (in_bom yes) (on_board yes) (dnp no) (fields_autoplaced)
    (property "Reference" "C53" (at 254 166.3635 90)
      (effects (font (size 1.27 1.27) (thickness 0.15)) (justify left bottom))
    )
    (property "Value" "C_1u_0402" (at 266.7 149.86 0)
      (effects (font (size 1.27 1.27) (thickness 0.15)) (justify left bottom) hide)
    )
    (property "Footprint" "scalenode-cm4-baseboard-footprints:C_0402_1005Metric" (at 269.24 149.86 0)
      (effects (font (size 1.27 1.27) (thickness 0.15)) (justify left bottom) hide)
    )
    (property "Datasheet" "https://product.tdk.com/en/search/capacitor/ceramic/mlcc/info?part_no=C1005X6S1A105K050BC" (at 271.78 149.86 0)
      (effects (font (size 1.27 1.27) (thickness 0.15)) (justify left bottom) hide)
    )
    (property "Manufacturer" "TDK" (at 276.86 149.86 0)
      (effects (font (size 1.27 1.27) (thickness 0.15)) (justify left bottom) hide)
    )
    (property "MPN" "C1005X6S1A105K050BC" (at 274.32 149.86 0)
      (effects (font (size 1.27 1.27) (thickness 0.15)) (justify left bottom) hide)
    )
    (property "Val" "1u" (at 254 168.9035 90)
      (effects (font (size 1.27 1.27) (thickness 0.15)) (justify left bottom))
    )
    (property "License" "Apache-2.0" (at 279.4 149.86 0)
      (effects (font (size 1.27 1.27) (thickness 0.15)) (justify left bottom) hide)
    )
    (property "Author" "Antmicro" (at 281.94 149.86 0)
      (effects (font (size 1.27 1.27) (thickness 0.15)) (justify left bottom) hide)
    )
    (property "Voltage" "" (at 284.48 149.86 0)
      (effects (font (size 1.27 1.27)) (justify left bottom) hide)
    )
    (property "Dielectric" "" (at 287.02 149.86 0)
      (effects (font (size 1.27 1.27)) (justify left bottom) hide)
    )
    (pin "1")
    (pin "2")
    (instances
      (project "scalenode-cm4-baseboard"
        (path ""
          (reference "C53") (unit 1)
        )
      )
    )
  )

  (symbol (lib_id "scalenode-cm4-baseboard:GND") (at 264.16 171.45 0) (mirror y) (unit 1)
    (in_bom yes) (on_board yes) (dnp no) (fields_autoplaced)
    (property "Reference" "#PWR044" (at 255.27 173.99 0)
      (effects (font (size 1.27 1.27) (thickness 0.15)) (justify left bottom) hide)
    )
    (property "Value" "GND" (at 266.1703 176.53 0)
      (effects (font (size 1.27 1.27) (thickness 0.15)) (justify left bottom))
    )
    (property "Footprint" "" (at 255.27 179.07 0)
      (effects (font (size 1.27 1.27) (thickness 0.15)) (justify left bottom) hide)
    )
    (property "Datasheet" "" (at 255.27 184.15 0)
      (effects (font (size 1.27 1.27) (thickness 0.15)) (justify left bottom) hide)
    )
    (property "Author" "Antmicro" (at 255.27 179.07 0)
      (effects (font (size 1.27 1.27) (thickness 0.15)) (justify left bottom) hide)
    )
    (property "License" "Apache-2.0" (at 255.27 181.61 0)
      (effects (font (size 1.27 1.27) (thickness 0.15)) (justify left bottom) hide)
    )
    (pin "1")
    (instances
      (project "scalenode-cm4-baseboard"
        (path ""
          (reference "#PWR044") (unit 1)
        )
      )
    )
  )

  (symbol (lib_id "scalenode-cm4-baseboard:GND") (at 256.54 171.45 0) (mirror y) (unit 1)
    (in_bom yes) (on_board yes) (dnp no) (fields_autoplaced)
    (property "Reference" "#PWR043" (at 247.65 173.99 0)
      (effects (font (size 1.27 1.27) (thickness 0.15)) (justify left bottom) hide)
    )
    (property "Value" "GND" (at 258.5503 176.53 0)
      (effects (font (size 1.27 1.27) (thickness 0.15)) (justify left bottom))
    )
    (property "Footprint" "" (at 247.65 179.07 0)
      (effects (font (size 1.27 1.27) (thickness 0.15)) (justify left bottom) hide)
    )
    (property "Datasheet" "" (at 247.65 184.15 0)
      (effects (font (size 1.27 1.27) (thickness 0.15)) (justify left bottom) hide)
    )
    (property "Author" "Antmicro" (at 247.65 179.07 0)
      (effects (font (size 1.27 1.27) (thickness 0.15)) (justify left bottom) hide)
    )
    (property "License" "Apache-2.0" (at 247.65 181.61 0)
      (effects (font (size 1.27 1.27) (thickness 0.15)) (justify left bottom) hide)
    )
    (pin "1")
    (instances
      (project "scalenode-cm4-baseboard"
        (path ""
          (reference "#PWR043") (unit 1)
        )
      )
    )
  )

  (symbol (lib_id "scalenode-cm4-baseboard:C_100n_0402") (at 55.88 71.12 90) (mirror x) (unit 1)
    (in_bom yes) (on_board yes) (dnp no)
    (property "Reference" "C56" (at 55.88 72.39 90)
      (effects (font (size 1.27 1.27) (thickness 0.15)) (justify right bottom))
    )
    (property "Value" "C_100n_0402" (at 66.04 91.44 0)
      (effects (font (size 1.27 1.27) (thickness 0.15)) (justify left bottom) hide)
    )
    (property "Footprint" "scalenode-cm4-baseboard-footprints:C_0402_1005Metric" (at 68.58 91.44 0)
      (effects (font (size 1.27 1.27) (thickness 0.15)) (justify left bottom) hide)
    )
    (property "Datasheet" "https://www.murata.com/products/productdetail?partno=GRM155R61H104KE14%23" (at 71.12 91.44 0)
      (effects (font (size 1.27 1.27) (thickness 0.15)) (justify left bottom) hide)
    )
    (property "Manufacturer" "Murata" (at 76.2 91.44 0)
      (effects (font (size 1.27 1.27) (thickness 0.15)) (justify left bottom) hide)
    )
    (property "MPN" "GRM155R61H104KE14D" (at 73.66 91.44 0)
      (effects (font (size 1.27 1.27) (thickness 0.15)) (justify left bottom) hide)
    )
    (property "Val" "100n" (at 55.88 74.93 90)
      (effects (font (size 1.27 1.27) (thickness 0.15)) (justify right top))
    )
    (property "License" "Apache-2.0" (at 78.74 91.44 0)
      (effects (font (size 1.27 1.27) (thickness 0.15)) (justify left bottom) hide)
    )
    (property "Author" "Antmicro" (at 81.28 91.44 0)
      (effects (font (size 1.27 1.27) (thickness 0.15)) (justify left bottom) hide)
    )
    (property "Voltage" "50V" (at 83.82 91.44 0)
      (effects (font (size 1.27 1.27)) (justify left bottom) hide)
    )
    (property "Dielectric" "X5R" (at 86.36 91.44 0)
      (effects (font (size 1.27 1.27)) (justify left bottom) hide)
    )
    (pin "1")
    (pin "2")
    (instances
      (project "scalenode-cm4-baseboard"
        (path ""
          (reference "C56") (unit 1)
        )
      )
    )
  )

  (symbol (lib_id "scalenode-cm4-baseboard:GND") (at 50.8 86.36 0) (mirror y) (unit 1)
    (in_bom yes) (on_board yes) (dnp no) (fields_autoplaced)
    (property "Reference" "#PWR047" (at 41.91 88.9 0)
      (effects (font (size 1.27 1.27) (thickness 0.15)) (justify left bottom) hide)
    )
    (property "Value" "GND" (at 52.8103 91.44 0)
      (effects (font (size 1.27 1.27) (thickness 0.15)) (justify left bottom))
    )
    (property "Footprint" "" (at 41.91 93.98 0)
      (effects (font (size 1.27 1.27) (thickness 0.15)) (justify left bottom) hide)
    )
    (property "Datasheet" "" (at 41.91 99.06 0)
      (effects (font (size 1.27 1.27) (thickness 0.15)) (justify left bottom) hide)
    )
    (property "Author" "Antmicro" (at 41.91 93.98 0)
      (effects (font (size 1.27 1.27) (thickness 0.15)) (justify left bottom) hide)
    )
    (property "License" "Apache-2.0" (at 41.91 96.52 0)
      (effects (font (size 1.27 1.27) (thickness 0.15)) (justify left bottom) hide)
    )
    (pin "1")
    (instances
      (project "scalenode-cm4-baseboard"
        (path ""
          (reference "#PWR047") (unit 1)
        )
      )
    )
  )

  (symbol (lib_id "scalenode-cm4-baseboard:CAS-120TA") (at 147.32 63.5 0) (mirror y) (unit 1)
    (in_bom yes) (on_board yes) (dnp no) (fields_autoplaced)
    (property "Reference" "S1" (at 147.5244 55.88 0)
      (effects (font (size 1.27 1.27) (thickness 0.15)) (justify left bottom))
    )
    (property "Value" "CAS-120TA" (at 147.5244 58.42 0)
      (effects (font (size 1.27 1.27) (thickness 0.15)) (justify left bottom))
    )
    (property "Footprint" "scalenode-cm4-baseboard-footprints:Switch_Slide_CAS-120TA" (at 121.92 71.12 0)
      (effects (font (size 1.27 1.27) (thickness 0.15)) (justify left bottom) hide)
    )
    (property "Datasheet" "https://www.nidec-components.com/e/catalog/switch/cas.pdf" (at 121.92 73.66 0)
      (effects (font (size 1.27 1.27) (thickness 0.15)) (justify left bottom) hide)
    )
    (property "MPN" "CAS-120TA" (at 121.92 76.2 0)
      (effects (font (size 1.27 1.27) (thickness 0.15)) (justify left bottom) hide)
    )
    (property "Manufacturer" "Nidec Components" (at 121.92 78.74 0)
      (effects (font (size 1.27 1.27) (thickness 0.15)) (justify left bottom) hide)
    )
    (property "Author" "Antmicro" (at 121.92 81.28 0)
      (effects (font (size 1.27 1.27) (thickness 0.15)) (justify left bottom) hide)
    )
    (property "License" "Apache-2.0" (at 121.92 83.82 0)
      (effects (font (size 1.27 1.27) (thickness 0.15)) (justify left bottom) hide)
    )
    (pin "1")
    (pin "2")
    (pin "3")
    (instances
      (project "scalenode-cm4-baseboard"
        (path ""
          (reference "S1") (unit 1)
        )
      )
    )
  )

  (symbol (lib_id "scalenode-cm4-baseboard:GND") (at 139.7 92.71 0) (unit 1)
    (in_bom yes) (on_board yes) (dnp no) (fields_autoplaced)
    (property "Reference" "#PWR012" (at 148.59 95.25 0)
      (effects (font (size 1.27 1.27) (thickness 0.15)) (justify left bottom) hide)
    )
    (property "Value" "GND" (at 137.6898 97.79 0)
      (effects (font (size 1.27 1.27) (thickness 0.15)) (justify left bottom))
    )
    (property "Footprint" "" (at 148.59 100.33 0)
      (effects (font (size 1.27 1.27) (thickness 0.15)) (justify left bottom) hide)
    )
    (property "Datasheet" "" (at 148.59 105.41 0)
      (effects (font (size 1.27 1.27) (thickness 0.15)) (justify left bottom) hide)
    )
    (property "Author" "Antmicro" (at 148.59 100.33 0)
      (effects (font (size 1.27 1.27) (thickness 0.15)) (justify left bottom) hide)
    )
    (property "License" "Apache-2.0" (at 148.59 102.87 0)
      (effects (font (size 1.27 1.27) (thickness 0.15)) (justify left bottom) hide)
    )
    (pin "1")
    (instances
      (project "scalenode-cm4-baseboard"
        (path ""
          (reference "#PWR012") (unit 1)
        )
      )
    )
  )

  (symbol (lib_id "scalenode-cm4-baseboard:R_220R_0402") (at 335.28 168.91 0) (unit 1)
    (in_bom yes) (on_board yes) (dnp no)
    (property "Reference" "R60" (at 334.01 167.64 0)
      (effects (font (size 1.27 1.27) (thickness 0.15)) (justify left bottom))
    )
    (property "Value" "R_220R_0402" (at 355.6 181.61 0)
      (effects (font (size 1.27 1.27) (thickness 0.15)) (justify left bottom) hide)
    )
    (property "Footprint" "scalenode-cm4-baseboard-footprints:R_0402_1005Metric" (at 355.6 184.15 0)
      (effects (font (size 1.27 1.27) (thickness 0.15)) (justify left bottom) hide)
    )
    (property "Datasheet" "https://www.bourns.com/docs/product-datasheets/cr.pdf" (at 355.6 186.69 0)
      (effects (font (size 1.27 1.27) (thickness 0.15)) (justify left bottom) hide)
    )
    (property "Manufacturer" "Bourns" (at 355.6 191.77 0)
      (effects (font (size 1.27 1.27) (thickness 0.15)) (justify left bottom) hide)
    )
    (property "MPN" "CR0402-FX-2200GLF" (at 355.6 189.23 0)
      (effects (font (size 1.27 1.27) (thickness 0.15)) (justify left bottom) hide)
    )
    (property "Val" "220R" (at 339.09 167.64 0)
      (effects (font (size 1.27 1.27) (thickness 0.15)) (justify left bottom))
    )
    (property "License" "Apache-2.0" (at 355.6 194.31 0)
      (effects (font (size 1.27 1.27) (thickness 0.15)) (justify left bottom) hide)
    )
    (property "Author" "Antmicro" (at 355.6 196.85 0)
      (effects (font (size 1.27 1.27) (thickness 0.15)) (justify left bottom) hide)
    )
    (property "Tolerance" "1%" (at 355.6 179.07 0)
      (effects (font (size 1.27 1.27)) (justify left bottom) hide)
    )
    (pin "1")
    (pin "2")
    (instances
      (project "scalenode-cm4-baseboard"
        (path ""
          (reference "R60") (unit 1)
        )
      )
    )
  )

  (symbol (lib_id "scalenode-cm4-baseboard:R_220R_0402") (at 354.33 165.1 0) (mirror y) (unit 1)
    (in_bom no) (on_board yes) (dnp yes)
    (property "Reference" "R61" (at 354.33 161.29 0)
      (effects (font (size 1.27 1.27) (thickness 0.15)) (justify left bottom))
    )
    (property "Value" "R_220R_0402" (at 334.01 177.8 0)
      (effects (font (size 1.27 1.27) (thickness 0.15)) (justify left bottom) hide)
    )
    (property "Footprint" "scalenode-cm4-baseboard-footprints:R_0402_1005Metric" (at 334.01 180.34 0)
      (effects (font (size 1.27 1.27) (thickness 0.15)) (justify left bottom) hide)
    )
    (property "Datasheet" "https://www.bourns.com/docs/product-datasheets/cr.pdf" (at 334.01 182.88 0)
      (effects (font (size 1.27 1.27) (thickness 0.15)) (justify left bottom) hide)
    )
    (property "Manufacturer" "Bourns" (at 334.01 187.96 0)
      (effects (font (size 1.27 1.27) (thickness 0.15)) (justify left bottom) hide)
    )
    (property "MPN" "CR0402-FX-2200GLF" (at 334.01 185.42 0)
      (effects (font (size 1.27 1.27) (thickness 0.15)) (justify left bottom) hide)
    )
    (property "Val" "220R" (at 354.33 163.83 0)
      (effects (font (size 1.27 1.27) (thickness 0.15)) (justify left bottom))
    )
    (property "DNP" "DNP" (at 351.79 165.1 0)
      (effects (font (size 1 1)))
    )
    (property "License" "Apache-2.0" (at 334.01 190.5 0)
      (effects (font (size 1.27 1.27) (thickness 0.15)) (justify left bottom) hide)
    )
    (property "Author" "Antmicro" (at 334.01 193.04 0)
      (effects (font (size 1.27 1.27) (thickness 0.15)) (justify left bottom) hide)
    )
    (property "Tolerance" "1%" (at 334.01 175.26 0)
      (effects (font (size 1.27 1.27)) (justify left bottom) hide)
    )
    (pin "1")
    (pin "2")
    (instances
      (project "scalenode-cm4-baseboard"
        (path ""
          (reference "R61") (unit 1)
        )
      )
    )
  )

  (symbol (lib_id "scalenode-cm4-baseboard:R_220R_0402") (at 340.36 171.45 0) (mirror y) (unit 1)
    (in_bom yes) (on_board yes) (dnp no)
    (property "Reference" "R56" (at 337.82 172.72 0)
      (effects (font (size 1.27 1.27) (thickness 0.15)) (justify left top))
    )
    (property "Value" "R_220R_0402" (at 320.04 184.15 0)
      (effects (font (size 1.27 1.27) (thickness 0.15)) (justify left bottom) hide)
    )
    (property "Footprint" "scalenode-cm4-baseboard-footprints:R_0402_1005Metric" (at 320.04 186.69 0)
      (effects (font (size 1.27 1.27) (thickness 0.15)) (justify left bottom) hide)
    )
    (property "Datasheet" "https://www.bourns.com/docs/product-datasheets/cr.pdf" (at 320.04 189.23 0)
      (effects (font (size 1.27 1.27) (thickness 0.15)) (justify left bottom) hide)
    )
    (property "Manufacturer" "Bourns" (at 320.04 194.31 0)
      (effects (font (size 1.27 1.27) (thickness 0.15)) (justify left bottom) hide)
    )
    (property "MPN" "CR0402-FX-2200GLF" (at 320.04 191.77 0)
      (effects (font (size 1.27 1.27) (thickness 0.15)) (justify left bottom) hide)
    )
    (property "Val" "220R" (at 339.09 172.72 0)
      (effects (font (size 1.27 1.27) (thickness 0.15)) (justify right top))
    )
    (property "License" "Apache-2.0" (at 320.04 196.85 0)
      (effects (font (size 1.27 1.27) (thickness 0.15)) (justify left bottom) hide)
    )
    (property "Author" "Antmicro" (at 320.04 199.39 0)
      (effects (font (size 1.27 1.27) (thickness 0.15)) (justify left bottom) hide)
    )
    (property "Tolerance" "1%" (at 320.04 181.61 0)
      (effects (font (size 1.27 1.27)) (justify left bottom) hide)
    )
    (pin "1")
    (pin "2")
    (instances
      (project "scalenode-cm4-baseboard"
        (path ""
          (reference "R56") (unit 1)
        )
      )
    )
  )

  (symbol (lib_id "scalenode-cm4-baseboard:R_220R_0402") (at 349.25 175.26 0) (unit 1)
    (in_bom no) (on_board yes) (dnp yes)
    (property "Reference" "R57" (at 349.2657 179.07 0)
      (effects (font (size 1.27 1.27) (thickness 0.15)) (justify left bottom))
    )
    (property "Value" "R_220R_0402" (at 369.57 187.96 0)
      (effects (font (size 1.27 1.27) (thickness 0.15)) (justify left bottom) hide)
    )
    (property "Footprint" "scalenode-cm4-baseboard-footprints:R_0402_1005Metric" (at 369.57 190.5 0)
      (effects (font (size 1.27 1.27) (thickness 0.15)) (justify left bottom) hide)
    )
    (property "Datasheet" "https://www.bourns.com/docs/product-datasheets/cr.pdf" (at 369.57 193.04 0)
      (effects (font (size 1.27 1.27) (thickness 0.15)) (justify left bottom) hide)
    )
    (property "Manufacturer" "Bourns" (at 369.57 198.12 0)
      (effects (font (size 1.27 1.27) (thickness 0.15)) (justify left bottom) hide)
    )
    (property "MPN" "CR0402-FX-2200GLF" (at 369.57 195.58 0)
      (effects (font (size 1.27 1.27) (thickness 0.15)) (justify left bottom) hide)
    )
    (property "Val" "220R" (at 349.2657 181.61 0)
      (effects (font (size 1.27 1.27) (thickness 0.15)) (justify left bottom))
    )
    (property "DNP" "DNP" (at 351.79 175.26 0)
      (effects (font (size 1 1)))
    )
    (property "License" "Apache-2.0" (at 369.57 200.66 0)
      (effects (font (size 1.27 1.27) (thickness 0.15)) (justify left bottom) hide)
    )
    (property "Author" "Antmicro" (at 369.57 203.2 0)
      (effects (font (size 1.27 1.27) (thickness 0.15)) (justify left bottom) hide)
    )
    (property "Tolerance" "1%" (at 369.57 185.42 0)
      (effects (font (size 1.27 1.27)) (justify left bottom) hide)
    )
    (pin "1")
    (pin "2")
    (instances
      (project "scalenode-cm4-baseboard"
        (path ""
          (reference "R57") (unit 1)
        )
      )
    )
  )

  (symbol (lib_id "scalenode-cm4-baseboard:PWR_FLAG") (at 288.29 152.4 0) (unit 1)
    (in_bom yes) (on_board yes) (dnp no) (fields_autoplaced)
    (property "Reference" "#FLG0104" (at 288.29 150.495 0)
      (effects (font (size 1.27 1.27)) hide)
    )
    (property "Value" "PWR_FLAG" (at 288.29 147.32 0)
      (effects (font (size 1.27 1.27)))
    )
    (property "Footprint" "" (at 288.29 152.4 0)
      (effects (font (size 1.27 1.27)) hide)
    )
    (property "Datasheet" "" (at 288.29 152.4 0)
      (effects (font (size 1.27 1.27)) hide)
    )
    (pin "1")
    (instances
      (project "scalenode-cm4-baseboard"
        (path ""
          (reference "#FLG0104") (unit 1)
        )
      )
    )
  )

  (symbol (lib_id "scalenode-cm4-baseboard:PWR_FLAG") (at 218.44 52.07 0) (unit 1)
    (in_bom yes) (on_board yes) (dnp no) (fields_autoplaced)
    (property "Reference" "#FLG0102" (at 218.44 50.165 0)
      (effects (font (size 1.27 1.27)) hide)
    )
    (property "Value" "PWR_FLAG" (at 218.44 46.99 0)
      (effects (font (size 1.27 1.27)))
    )
    (property "Footprint" "" (at 218.44 52.07 0)
      (effects (font (size 1.27 1.27)) hide)
    )
    (property "Datasheet" "" (at 218.44 52.07 0)
      (effects (font (size 1.27 1.27)) hide)
    )
    (pin "1")
    (instances
      (project "scalenode-cm4-baseboard"
        (path ""
          (reference "#FLG0102") (unit 1)
        )
      )
    )
  )

  (symbol (lib_id "scalenode-cm4-baseboard:GND") (at 67.31 86.36 0) (mirror y) (unit 1)
    (in_bom yes) (on_board yes) (dnp no) (fields_autoplaced)
    (property "Reference" "#PWR0118" (at 58.42 88.9 0)
      (effects (font (size 1.27 1.27) (thickness 0.15)) (justify left bottom) hide)
    )
    (property "Value" "GND" (at 69.3203 91.44 0)
      (effects (font (size 1.27 1.27) (thickness 0.15)) (justify left bottom))
    )
    (property "Footprint" "" (at 58.42 93.98 0)
      (effects (font (size 1.27 1.27) (thickness 0.15)) (justify left bottom) hide)
    )
    (property "Datasheet" "" (at 58.42 99.06 0)
      (effects (font (size 1.27 1.27) (thickness 0.15)) (justify left bottom) hide)
    )
    (property "Author" "Antmicro" (at 58.42 93.98 0)
      (effects (font (size 1.27 1.27) (thickness 0.15)) (justify left bottom) hide)
    )
    (property "License" "Apache-2.0" (at 58.42 96.52 0)
      (effects (font (size 1.27 1.27) (thickness 0.15)) (justify left bottom) hide)
    )
    (pin "1")
    (instances
      (project "scalenode-cm4-baseboard"
        (path ""
          (reference "#PWR0118") (unit 1)
        )
      )
    )
  )

  (symbol (lib_id "scalenode-cm4-baseboard:GND") (at 55.88 86.36 0) (mirror y) (unit 1)
    (in_bom yes) (on_board yes) (dnp no) (fields_autoplaced)
    (property "Reference" "#PWR0119" (at 46.99 88.9 0)
      (effects (font (size 1.27 1.27) (thickness 0.15)) (justify left bottom) hide)
    )
    (property "Value" "GND" (at 57.8903 91.44 0)
      (effects (font (size 1.27 1.27) (thickness 0.15)) (justify left bottom))
    )
    (property "Footprint" "" (at 46.99 93.98 0)
      (effects (font (size 1.27 1.27) (thickness 0.15)) (justify left bottom) hide)
    )
    (property "Datasheet" "" (at 46.99 99.06 0)
      (effects (font (size 1.27 1.27) (thickness 0.15)) (justify left bottom) hide)
    )
    (property "Author" "Antmicro" (at 46.99 93.98 0)
      (effects (font (size 1.27 1.27) (thickness 0.15)) (justify left bottom) hide)
    )
    (property "License" "Apache-2.0" (at 46.99 96.52 0)
      (effects (font (size 1.27 1.27) (thickness 0.15)) (justify left bottom) hide)
    )
    (pin "1")
    (instances
      (project "scalenode-cm4-baseboard"
        (path ""
          (reference "#PWR0119") (unit 1)
        )
      )
    )
  )
)
